FILE_TYPE = MACRO_DRAWING;
SET COLOR_WIRE YELLOW;
SET COLOR_PROP ORANGE;
SET COLOR_DOT WHITE;
SET COLOR_ARC YELLOW;
SET COLOR_BODY GREEN;
SET COLOR_NOTE PURPLE;
SET PROP_DISPLAY VALUE;
SET PAGE_NUMBER P93;
FORCEADD UNIVERSAL_GND..1
(-1850 50);
FORCEPROP 3 LASTPIN (-1850 100) SIG_NAME GND\g
J 0
(-1840 110);
DISPLAY 0.659574 (-1840 110);
PAINT MONO (-1840 110);
DISPLAY INVISIBLE (-1840 110);
FORCEPROP 2 LAST CDS_LIB logical_power
J 0
(-1850 50);
PAINT MONO (-1850 50);
DISPLAY INVISIBLE (-1850 50);
FORCEPROP 1 LAST HDL_POWER GND
J 1
(-1825 -25);
DISPLAY 0.872340 (-1825 -25);
PAINT GREEN (-1825 -25);
DISPLAY INVISIBLE (-1825 -25);
FORCEPROP 1 LAST PATH I1
J 0
(-1775 50);
DISPLAY 0.872340 (-1775 50);
PAINT AQUA (-1775 50);
DISPLAY INVISIBLE (-1775 50);
FORCEADD OFFPAGE..1
(-3000 2075);
FORCEPROP 2 LAST $XR1 92 
J 0
(-3311 2075);
DISPLAY 0.638298 (-3311 2075);
PAINT MONO (-3311 2075);
FORCEPROP 2 LAST $XR0 25 
J 0
(-3221 2075);
DISPLAY 0.638298 (-3221 2075);
PAINT MONO (-3221 2075);
FORCEPROP 2 LAST CDS_LIB standard
J 0
(-3000 2075);
PAINT MONO (-3000 2075);
DISPLAY INVISIBLE (-3000 2075);
FORCEPROP 1 LAST OFFPAGE TRUE
J 0
(-2675 1950);
DISPLAY 0.872340 (-2675 1950);
DISPLAY INVISIBLE (-2675 1950);
FORCEPROP 1 LAST COMMENT_BODY TRUE
J 0
(-2875 1975);
DISPLAY 0.872340 (-2875 1975);
PAINT GREEN (-2875 1975);
DISPLAY INVISIBLE (-2875 1975);
FORCEPROP 2 LAST PATH I10
J 0
(-2950 2150);
DISPLAY 1.021277 (-2950 2150);
DISPLAY INVISIBLE (-2950 2150);
FORCEADD TAP..1
(-425 3525);
FORCEPROP 3 LASTPIN (-475 3525) SIG_NAME M_F_CPU0_SA_DQ<13>
J 0
(-465 3535);
DISPLAY 0.659574 (-465 3535);
PAINT MONO (-465 3535);
DISPLAY INVISIBLE (-465 3535);
FORCEPROP 1 LASTPIN (-475 3525) BN 13
J 0
(-487 3533);
DISPLAY 0.680851 (-487 3533);
PAINT GREEN (-487 3533);
FORCEPROP 2 LAST CDS_LIB standard
J 0
(-425 3525);
PAINT MONO (-425 3525);
DISPLAY INVISIBLE (-425 3525);
FORCEPROP 1 LAST BODY_TYPE PLUMBING
J 0
(-425 3575);
DISPLAY 0.872340 (-425 3575);
PAINT GREEN (-425 3575);
DISPLAY INVISIBLE (-425 3575);
FORCEPROP 1 LAST HDL_TAP TRUE
J 0
(-100 3400);
DISPLAY 0.872340 (-100 3400);
DISPLAY INVISIBLE (-100 3400);
FORCEPROP 1 LAST PATH I100
J 0
(-427 3525);
DISPLAY 0.872340 (-427 3525);
PAINT GREEN (-427 3525);
DISPLAY INVISIBLE (-427 3525);
FORCEADD TAP..1
(-425 3575);
FORCEPROP 3 LASTPIN (-475 3575) SIG_NAME M_F_CPU0_SA_DQ<14>
J 0
(-465 3585);
DISPLAY 0.659574 (-465 3585);
PAINT MONO (-465 3585);
DISPLAY INVISIBLE (-465 3585);
FORCEPROP 1 LASTPIN (-475 3575) BN 14
J 0
(-487 3583);
DISPLAY 0.680851 (-487 3583);
PAINT GREEN (-487 3583);
FORCEPROP 2 LAST CDS_LIB standard
J 0
(-425 3575);
PAINT MONO (-425 3575);
DISPLAY INVISIBLE (-425 3575);
FORCEPROP 1 LAST BODY_TYPE PLUMBING
J 0
(-425 3625);
DISPLAY 0.872340 (-425 3625);
PAINT GREEN (-425 3625);
DISPLAY INVISIBLE (-425 3625);
FORCEPROP 1 LAST HDL_TAP TRUE
J 0
(-100 3450);
DISPLAY 0.872340 (-100 3450);
DISPLAY INVISIBLE (-100 3450);
FORCEPROP 1 LAST PATH I101
J 0
(-427 3575);
DISPLAY 0.872340 (-427 3575);
PAINT GREEN (-427 3575);
DISPLAY INVISIBLE (-427 3575);
FORCEADD TAP..1
(-425 3725);
FORCEPROP 3 LASTPIN (-475 3725) SIG_NAME M_F_CPU0_SA_DQ<17>
J 0
(-465 3735);
DISPLAY 0.659574 (-465 3735);
PAINT MONO (-465 3735);
DISPLAY INVISIBLE (-465 3735);
FORCEPROP 1 LASTPIN (-475 3725) BN 17
J 0
(-487 3733);
DISPLAY 0.680851 (-487 3733);
PAINT GREEN (-487 3733);
FORCEPROP 2 LAST CDS_LIB standard
J 0
(-425 3725);
PAINT MONO (-425 3725);
DISPLAY INVISIBLE (-425 3725);
FORCEPROP 1 LAST BODY_TYPE PLUMBING
J 0
(-425 3775);
DISPLAY 0.872340 (-425 3775);
PAINT GREEN (-425 3775);
DISPLAY INVISIBLE (-425 3775);
FORCEPROP 1 LAST HDL_TAP TRUE
J 0
(-100 3600);
DISPLAY 0.872340 (-100 3600);
DISPLAY INVISIBLE (-100 3600);
FORCEPROP 1 LAST PATH I102
J 0
(-427 3725);
DISPLAY 0.872340 (-427 3725);
PAINT GREEN (-427 3725);
DISPLAY INVISIBLE (-427 3725);
FORCEADD TAP..1
(-425 3775);
FORCEPROP 3 LASTPIN (-475 3775) SIG_NAME M_F_CPU0_SA_DQ<18>
J 0
(-465 3785);
DISPLAY 0.659574 (-465 3785);
PAINT MONO (-465 3785);
DISPLAY INVISIBLE (-465 3785);
FORCEPROP 1 LASTPIN (-475 3775) BN 18
J 0
(-487 3783);
DISPLAY 0.680851 (-487 3783);
PAINT GREEN (-487 3783);
FORCEPROP 2 LAST CDS_LIB standard
J 0
(-425 3775);
PAINT MONO (-425 3775);
DISPLAY INVISIBLE (-425 3775);
FORCEPROP 1 LAST BODY_TYPE PLUMBING
J 0
(-425 3825);
DISPLAY 0.872340 (-425 3825);
PAINT GREEN (-425 3825);
DISPLAY INVISIBLE (-425 3825);
FORCEPROP 1 LAST HDL_TAP TRUE
J 0
(-100 3650);
DISPLAY 0.872340 (-100 3650);
DISPLAY INVISIBLE (-100 3650);
FORCEPROP 1 LAST PATH I103
J 0
(-427 3775);
DISPLAY 0.872340 (-427 3775);
PAINT GREEN (-427 3775);
DISPLAY INVISIBLE (-427 3775);
FORCEADD TAP..1
(-425 3825);
FORCEPROP 3 LASTPIN (-475 3825) SIG_NAME M_F_CPU0_SA_DQ<19>
J 0
(-465 3835);
DISPLAY 0.659574 (-465 3835);
PAINT MONO (-465 3835);
DISPLAY INVISIBLE (-465 3835);
FORCEPROP 1 LASTPIN (-475 3825) BN 19
J 0
(-487 3833);
DISPLAY 0.680851 (-487 3833);
PAINT GREEN (-487 3833);
FORCEPROP 2 LAST CDS_LIB standard
J 0
(-425 3825);
PAINT MONO (-425 3825);
DISPLAY INVISIBLE (-425 3825);
FORCEPROP 1 LAST BODY_TYPE PLUMBING
J 0
(-425 3875);
DISPLAY 0.872340 (-425 3875);
PAINT GREEN (-425 3875);
DISPLAY INVISIBLE (-425 3875);
FORCEPROP 1 LAST HDL_TAP TRUE
J 0
(-100 3700);
DISPLAY 0.872340 (-100 3700);
DISPLAY INVISIBLE (-100 3700);
FORCEPROP 1 LAST PATH I104
J 0
(-427 3825);
DISPLAY 0.872340 (-427 3825);
PAINT GREEN (-427 3825);
DISPLAY INVISIBLE (-427 3825);
FORCEADD TAP..1
(-425 3875);
FORCEPROP 3 LASTPIN (-475 3875) SIG_NAME M_F_CPU0_SA_DQ<20>
J 0
(-465 3885);
DISPLAY 0.659574 (-465 3885);
PAINT MONO (-465 3885);
DISPLAY INVISIBLE (-465 3885);
FORCEPROP 1 LASTPIN (-475 3875) BN 20
J 0
(-487 3883);
DISPLAY 0.680851 (-487 3883);
PAINT GREEN (-487 3883);
FORCEPROP 2 LAST CDS_LIB standard
J 0
(-425 3875);
PAINT MONO (-425 3875);
DISPLAY INVISIBLE (-425 3875);
FORCEPROP 1 LAST BODY_TYPE PLUMBING
J 0
(-425 3925);
DISPLAY 0.872340 (-425 3925);
PAINT GREEN (-425 3925);
DISPLAY INVISIBLE (-425 3925);
FORCEPROP 1 LAST HDL_TAP TRUE
J 0
(-100 3750);
DISPLAY 0.872340 (-100 3750);
DISPLAY INVISIBLE (-100 3750);
FORCEPROP 1 LAST PATH I105
J 0
(-427 3875);
DISPLAY 0.872340 (-427 3875);
PAINT GREEN (-427 3875);
DISPLAY INVISIBLE (-427 3875);
FORCEADD TAP..1
(-425 3675);
FORCEPROP 3 LASTPIN (-475 3675) SIG_NAME M_F_CPU0_SA_DQ<16>
J 0
(-465 3685);
DISPLAY 0.659574 (-465 3685);
PAINT MONO (-465 3685);
DISPLAY INVISIBLE (-465 3685);
FORCEPROP 1 LASTPIN (-475 3675) BN 16
J 0
(-487 3683);
DISPLAY 0.680851 (-487 3683);
PAINT GREEN (-487 3683);
FORCEPROP 2 LAST CDS_LIB standard
J 0
(-425 3675);
PAINT MONO (-425 3675);
DISPLAY INVISIBLE (-425 3675);
FORCEPROP 1 LAST BODY_TYPE PLUMBING
J 0
(-425 3725);
DISPLAY 0.872340 (-425 3725);
PAINT GREEN (-425 3725);
DISPLAY INVISIBLE (-425 3725);
FORCEPROP 1 LAST HDL_TAP TRUE
J 0
(-100 3550);
DISPLAY 0.872340 (-100 3550);
DISPLAY INVISIBLE (-100 3550);
FORCEPROP 1 LAST PATH I106
J 0
(-427 3675);
DISPLAY 0.872340 (-427 3675);
PAINT GREEN (-427 3675);
DISPLAY INVISIBLE (-427 3675);
FORCEADD TAP..1
(-425 3925);
FORCEPROP 3 LASTPIN (-475 3925) SIG_NAME M_F_CPU0_SA_DQ<21>
J 0
(-465 3935);
DISPLAY 0.659574 (-465 3935);
PAINT MONO (-465 3935);
DISPLAY INVISIBLE (-465 3935);
FORCEPROP 1 LASTPIN (-475 3925) BN 21
J 0
(-487 3933);
DISPLAY 0.680851 (-487 3933);
PAINT GREEN (-487 3933);
FORCEPROP 2 LAST CDS_LIB standard
J 0
(-425 3925);
PAINT MONO (-425 3925);
DISPLAY INVISIBLE (-425 3925);
FORCEPROP 1 LAST BODY_TYPE PLUMBING
J 0
(-425 3975);
DISPLAY 0.872340 (-425 3975);
PAINT GREEN (-425 3975);
DISPLAY INVISIBLE (-425 3975);
FORCEPROP 1 LAST HDL_TAP TRUE
J 0
(-100 3800);
DISPLAY 0.872340 (-100 3800);
DISPLAY INVISIBLE (-100 3800);
FORCEPROP 1 LAST PATH I107
J 0
(-427 3925);
DISPLAY 0.872340 (-427 3925);
PAINT GREEN (-427 3925);
DISPLAY INVISIBLE (-427 3925);
FORCEADD TAP..1
(-425 3975);
FORCEPROP 3 LASTPIN (-475 3975) SIG_NAME M_F_CPU0_SA_DQ<22>
J 0
(-465 3985);
DISPLAY 0.659574 (-465 3985);
PAINT MONO (-465 3985);
DISPLAY INVISIBLE (-465 3985);
FORCEPROP 1 LASTPIN (-475 3975) BN 22
J 0
(-487 3983);
DISPLAY 0.680851 (-487 3983);
PAINT GREEN (-487 3983);
FORCEPROP 2 LAST CDS_LIB standard
J 0
(-425 3975);
DISPLAY INVISIBLE (-425 3975);
FORCEPROP 1 LAST BODY_TYPE PLUMBING
J 0
(-425 4025);
DISPLAY 0.872340 (-425 4025);
PAINT GREEN (-425 4025);
DISPLAY INVISIBLE (-425 4025);
FORCEPROP 1 LAST HDL_TAP TRUE
J 0
(-100 3850);
DISPLAY 0.872340 (-100 3850);
DISPLAY INVISIBLE (-100 3850);
FORCEPROP 1 LAST PATH I108
J 0
(-427 3975);
DISPLAY 0.872340 (-427 3975);
PAINT GREEN (-427 3975);
DISPLAY INVISIBLE (-427 3975);
FORCEADD TAP..1
(-425 4025);
FORCEPROP 3 LASTPIN (-475 4025) SIG_NAME M_F_CPU0_SA_DQ<23>
J 0
(-465 4035);
DISPLAY 0.659574 (-465 4035);
PAINT MONO (-465 4035);
DISPLAY INVISIBLE (-465 4035);
FORCEPROP 1 LASTPIN (-475 4025) BN 23
J 0
(-487 4033);
DISPLAY 0.680851 (-487 4033);
PAINT GREEN (-487 4033);
FORCEPROP 2 LAST CDS_LIB standard
J 0
(-425 4025);
DISPLAY INVISIBLE (-425 4025);
FORCEPROP 1 LAST BODY_TYPE PLUMBING
J 0
(-425 4075);
DISPLAY 0.872340 (-425 4075);
PAINT GREEN (-425 4075);
DISPLAY INVISIBLE (-425 4075);
FORCEPROP 1 LAST HDL_TAP TRUE
J 0
(-100 3900);
DISPLAY 0.872340 (-100 3900);
DISPLAY INVISIBLE (-100 3900);
FORCEPROP 1 LAST PATH I109
J 0
(-427 4025);
DISPLAY 0.872340 (-427 4025);
PAINT GREEN (-427 4025);
DISPLAY INVISIBLE (-427 4025);
FORCEADD OFFPAGE..1
(-3000 2175);
FORCEPROP 2 LAST $XR3 92 
J 0
(-3252 2139);
DISPLAY 0.638298 (-3252 2139);
PAINT MONO (-3252 2139);
FORCEPROP 2 LAST $XR2 91 
J 0
(-3432 2175);
DISPLAY 0.638298 (-3432 2175);
PAINT MONO (-3432 2175);
FORCEPROP 2 LAST $XR1 90 
J 0
(-3342 2175);
DISPLAY 0.638298 (-3342 2175);
PAINT MONO (-3342 2175);
FORCEPROP 2 LAST $XR0 129 
J 0
(-3252 2175);
DISPLAY 0.638298 (-3252 2175);
PAINT MONO (-3252 2175);
FORCEPROP 2 LAST CDS_LIB standard
J 0
(-3000 2175);
PAINT MONO (-3000 2175);
DISPLAY INVISIBLE (-3000 2175);
FORCEPROP 1 LAST OFFPAGE TRUE
J 0
(-2675 2050);
DISPLAY 0.872340 (-2675 2050);
DISPLAY INVISIBLE (-2675 2050);
FORCEPROP 1 LAST COMMENT_BODY TRUE
J 0
(-2875 2075);
DISPLAY 0.872340 (-2875 2075);
PAINT GREEN (-2875 2075);
DISPLAY INVISIBLE (-2875 2075);
FORCEPROP 2 LAST PATH I11
J 0
(-2950 2250);
DISPLAY 1.021277 (-2950 2250);
DISPLAY INVISIBLE (-2950 2250);
FORCEADD TAP..1
(-425 4125);
FORCEPROP 3 LASTPIN (-475 4125) SIG_NAME M_F_CPU0_SA_DQ<25>
J 0
(-465 4135);
DISPLAY 0.659574 (-465 4135);
PAINT MONO (-465 4135);
DISPLAY INVISIBLE (-465 4135);
FORCEPROP 1 LASTPIN (-475 4125) BN 25
J 0
(-487 4133);
DISPLAY 0.680851 (-487 4133);
PAINT GREEN (-487 4133);
FORCEPROP 2 LAST CDS_LIB standard
J 0
(-425 4125);
DISPLAY INVISIBLE (-425 4125);
FORCEPROP 1 LAST BODY_TYPE PLUMBING
J 0
(-425 4175);
DISPLAY 0.872340 (-425 4175);
PAINT GREEN (-425 4175);
DISPLAY INVISIBLE (-425 4175);
FORCEPROP 1 LAST HDL_TAP TRUE
J 0
(-100 4000);
DISPLAY 0.872340 (-100 4000);
DISPLAY INVISIBLE (-100 4000);
FORCEPROP 1 LAST PATH I110
J 0
(-427 4125);
DISPLAY 0.872340 (-427 4125);
PAINT GREEN (-427 4125);
DISPLAY INVISIBLE (-427 4125);
FORCEADD TAP..1
(-425 4075);
FORCEPROP 3 LASTPIN (-475 4075) SIG_NAME M_F_CPU0_SA_DQ<24>
J 0
(-465 4085);
DISPLAY 0.659574 (-465 4085);
PAINT MONO (-465 4085);
DISPLAY INVISIBLE (-465 4085);
FORCEPROP 1 LASTPIN (-475 4075) BN 24
J 0
(-487 4083);
DISPLAY 0.680851 (-487 4083);
PAINT GREEN (-487 4083);
FORCEPROP 2 LAST CDS_LIB standard
J 0
(-425 4075);
DISPLAY INVISIBLE (-425 4075);
FORCEPROP 1 LAST BODY_TYPE PLUMBING
J 0
(-425 4125);
DISPLAY 0.872340 (-425 4125);
PAINT GREEN (-425 4125);
DISPLAY INVISIBLE (-425 4125);
FORCEPROP 1 LAST HDL_TAP TRUE
J 0
(-100 3950);
DISPLAY 0.872340 (-100 3950);
DISPLAY INVISIBLE (-100 3950);
FORCEPROP 1 LAST PATH I111
J 0
(-427 4075);
DISPLAY 0.872340 (-427 4075);
PAINT GREEN (-427 4075);
DISPLAY INVISIBLE (-427 4075);
FORCEADD TAP..1
(-425 4175);
FORCEPROP 3 LASTPIN (-475 4175) SIG_NAME M_F_CPU0_SA_DQ<26>
J 0
(-465 4185);
DISPLAY 0.659574 (-465 4185);
PAINT MONO (-465 4185);
DISPLAY INVISIBLE (-465 4185);
FORCEPROP 1 LASTPIN (-475 4175) BN 26
J 0
(-487 4183);
DISPLAY 0.680851 (-487 4183);
PAINT GREEN (-487 4183);
FORCEPROP 2 LAST CDS_LIB standard
J 0
(-425 4175);
DISPLAY INVISIBLE (-425 4175);
FORCEPROP 1 LAST BODY_TYPE PLUMBING
J 0
(-425 4225);
DISPLAY 0.872340 (-425 4225);
PAINT GREEN (-425 4225);
DISPLAY INVISIBLE (-425 4225);
FORCEPROP 1 LAST HDL_TAP TRUE
J 0
(-100 4050);
DISPLAY 0.872340 (-100 4050);
DISPLAY INVISIBLE (-100 4050);
FORCEPROP 1 LAST PATH I112
J 0
(-427 4175);
DISPLAY 0.872340 (-427 4175);
PAINT GREEN (-427 4175);
DISPLAY INVISIBLE (-427 4175);
FORCEADD TAP..1
(-425 4225);
FORCEPROP 3 LASTPIN (-475 4225) SIG_NAME M_F_CPU0_SA_DQ<27>
J 0
(-465 4235);
DISPLAY 0.659574 (-465 4235);
PAINT MONO (-465 4235);
DISPLAY INVISIBLE (-465 4235);
FORCEPROP 1 LASTPIN (-475 4225) BN 27
J 0
(-487 4233);
DISPLAY 0.680851 (-487 4233);
PAINT GREEN (-487 4233);
FORCEPROP 2 LAST CDS_LIB standard
J 0
(-425 4225);
DISPLAY INVISIBLE (-425 4225);
FORCEPROP 1 LAST BODY_TYPE PLUMBING
J 0
(-425 4275);
DISPLAY 0.872340 (-425 4275);
PAINT GREEN (-425 4275);
DISPLAY INVISIBLE (-425 4275);
FORCEPROP 1 LAST HDL_TAP TRUE
J 0
(-100 4100);
DISPLAY 0.872340 (-100 4100);
DISPLAY INVISIBLE (-100 4100);
FORCEPROP 1 LAST PATH I113
J 0
(-427 4225);
DISPLAY 0.872340 (-427 4225);
PAINT GREEN (-427 4225);
DISPLAY INVISIBLE (-427 4225);
FORCEADD TAP..1
(-425 4275);
FORCEPROP 3 LASTPIN (-475 4275) SIG_NAME M_F_CPU0_SA_DQ<28>
J 0
(-465 4285);
DISPLAY 0.659574 (-465 4285);
PAINT MONO (-465 4285);
DISPLAY INVISIBLE (-465 4285);
FORCEPROP 1 LASTPIN (-475 4275) BN 28
J 0
(-487 4283);
DISPLAY 0.680851 (-487 4283);
PAINT GREEN (-487 4283);
FORCEPROP 2 LAST CDS_LIB standard
J 0
(-425 4275);
DISPLAY INVISIBLE (-425 4275);
FORCEPROP 1 LAST BODY_TYPE PLUMBING
J 0
(-425 4325);
DISPLAY 0.872340 (-425 4325);
PAINT GREEN (-425 4325);
DISPLAY INVISIBLE (-425 4325);
FORCEPROP 1 LAST HDL_TAP TRUE
J 0
(-100 4150);
DISPLAY 0.872340 (-100 4150);
DISPLAY INVISIBLE (-100 4150);
FORCEPROP 1 LAST PATH I114
J 0
(-427 4275);
DISPLAY 0.872340 (-427 4275);
PAINT GREEN (-427 4275);
DISPLAY INVISIBLE (-427 4275);
FORCEADD TAP..1
(-425 4375);
FORCEPROP 3 LASTPIN (-475 4375) SIG_NAME M_F_CPU0_SA_DQ<30>
J 0
(-465 4385);
DISPLAY 0.659574 (-465 4385);
PAINT MONO (-465 4385);
DISPLAY INVISIBLE (-465 4385);
FORCEPROP 1 LASTPIN (-475 4375) BN 30
J 0
(-487 4383);
DISPLAY 0.680851 (-487 4383);
PAINT GREEN (-487 4383);
FORCEPROP 2 LAST CDS_LIB standard
J 0
(-425 4375);
DISPLAY INVISIBLE (-425 4375);
FORCEPROP 1 LAST BODY_TYPE PLUMBING
J 0
(-425 4425);
DISPLAY 0.872340 (-425 4425);
PAINT GREEN (-425 4425);
DISPLAY INVISIBLE (-425 4425);
FORCEPROP 1 LAST HDL_TAP TRUE
J 0
(-100 4250);
DISPLAY 0.872340 (-100 4250);
DISPLAY INVISIBLE (-100 4250);
FORCEPROP 1 LAST PATH I115
J 0
(-427 4375);
DISPLAY 0.872340 (-427 4375);
PAINT GREEN (-427 4375);
DISPLAY INVISIBLE (-427 4375);
FORCEADD TAP..1
(-425 4325);
FORCEPROP 3 LASTPIN (-475 4325) SIG_NAME M_F_CPU0_SA_DQ<29>
J 0
(-465 4335);
DISPLAY 0.659574 (-465 4335);
PAINT MONO (-465 4335);
DISPLAY INVISIBLE (-465 4335);
FORCEPROP 1 LASTPIN (-475 4325) BN 29
J 0
(-487 4333);
DISPLAY 0.680851 (-487 4333);
PAINT GREEN (-487 4333);
FORCEPROP 2 LAST CDS_LIB standard
J 0
(-425 4325);
DISPLAY INVISIBLE (-425 4325);
FORCEPROP 1 LAST BODY_TYPE PLUMBING
J 0
(-425 4375);
DISPLAY 0.872340 (-425 4375);
PAINT GREEN (-425 4375);
DISPLAY INVISIBLE (-425 4375);
FORCEPROP 1 LAST HDL_TAP TRUE
J 0
(-100 4200);
DISPLAY 0.872340 (-100 4200);
DISPLAY INVISIBLE (-100 4200);
FORCEPROP 1 LAST PATH I116
J 0
(-427 4325);
DISPLAY 0.872340 (-427 4325);
PAINT GREEN (-427 4325);
DISPLAY INVISIBLE (-427 4325);
FORCEADD OFFPAGE..1
(-3000 4450);
FORCEPROP 2 LAST $XR1 92 
J 0
(-3311 4450);
DISPLAY 0.638298 (-3311 4450);
PAINT MONO (-3311 4450);
FORCEPROP 2 LAST $XR0 25 
J 0
(-3221 4450);
DISPLAY 0.638298 (-3221 4450);
PAINT MONO (-3221 4450);
FORCEPROP 2 LAST CDS_LIB standard
J 0
(-3000 4450);
PAINT MONO (-3000 4450);
DISPLAY INVISIBLE (-3000 4450);
FORCEPROP 1 LAST OFFPAGE TRUE
J 0
(-2675 4325);
DISPLAY 0.872340 (-2675 4325);
DISPLAY INVISIBLE (-2675 4325);
FORCEPROP 1 LAST COMMENT_BODY TRUE
J 0
(-2875 4350);
DISPLAY 0.872340 (-2875 4350);
PAINT GREEN (-2875 4350);
DISPLAY INVISIBLE (-2875 4350);
FORCEPROP 2 LAST PATH I117
J 0
(-2950 4525);
DISPLAY 1.021277 (-2950 4525);
DISPLAY INVISIBLE (-2950 4525);
FORCEADD TAP..1
R 2
(-2075 4425);
FORCEPROP 3 LASTPIN (-2025 4425) SIG_NAME M_F_CPU0_SA_CA<6>
J 0
(-2015 4435);
DISPLAY 0.659574 (-2015 4435);
PAINT MONO (-2015 4435);
DISPLAY INVISIBLE (-2015 4435);
FORCEPROP 1 LASTPIN (-2025 4425) BN 6
J 2
(-2013 4433);
DISPLAY 0.680851 (-2013 4433);
PAINT GREEN (-2013 4433);
FORCEPROP 2 LAST CDS_LIB standard
J 0
(-2075 4425);
DISPLAY INVISIBLE (-2075 4425);
FORCEPROP 1 LAST BODY_TYPE PLUMBING
J 2
(-2075 4475);
DISPLAY 0.872340 (-2075 4475);
PAINT GREEN (-2075 4475);
DISPLAY INVISIBLE (-2075 4475);
FORCEPROP 1 LAST HDL_TAP TRUE
J 2
(-2400 4300);
DISPLAY 0.872340 (-2400 4300);
DISPLAY INVISIBLE (-2400 4300);
FORCEPROP 1 LAST PATH I118
J 2
(-2073 4425);
DISPLAY 0.872340 (-2073 4425);
PAINT GREEN (-2073 4425);
DISPLAY INVISIBLE (-2073 4425);
FORCEADD TAP..1
(-425 4425);
FORCEPROP 3 LASTPIN (-475 4425) SIG_NAME M_F_CPU0_SA_DQ<31>
J 0
(-465 4435);
DISPLAY 0.659574 (-465 4435);
PAINT MONO (-465 4435);
DISPLAY INVISIBLE (-465 4435);
FORCEPROP 1 LASTPIN (-475 4425) BN 31
J 0
(-487 4433);
DISPLAY 0.680851 (-487 4433);
PAINT GREEN (-487 4433);
FORCEPROP 2 LAST CDS_LIB standard
J 0
(-425 4425);
DISPLAY INVISIBLE (-425 4425);
FORCEPROP 1 LAST BODY_TYPE PLUMBING
J 0
(-425 4475);
DISPLAY 0.872340 (-425 4475);
PAINT GREEN (-425 4475);
DISPLAY INVISIBLE (-425 4475);
FORCEPROP 1 LAST HDL_TAP TRUE
J 0
(-100 4300);
DISPLAY 0.872340 (-100 4300);
DISPLAY INVISIBLE (-100 4300);
FORCEPROP 1 LAST PATH I119
J 0
(-427 4425);
DISPLAY 0.872340 (-427 4425);
PAINT GREEN (-427 4425);
DISPLAY INVISIBLE (-427 4425);
FORCEADD VCC_CORE..1
(-2900 2300);
FORCEPROP 3 LASTPIN (-2900 2250) SIG_NAME P3V3_AUX\g
J 0
(-2890 2260);
DISPLAY 0.659574 (-2890 2260);
PAINT MONO (-2890 2260);
DISPLAY INVISIBLE (-2890 2260);
FORCEPROP 1 LAST HDL_POWER P3V3_AUX
J 1
(-2900 2350);
DISPLAY 1.148936 (-2900 2350);
PAINT GREEN (-2900 2350);
FORCEPROP 2 LAST CDS_LIB logical_power
J 0
(-2900 2300);
PAINT MONO (-2900 2300);
DISPLAY INVISIBLE (-2900 2300);
FORCEPROP 1 LAST PATH I12
J 0
(-2850 2325);
DISPLAY 0.872340 (-2850 2325);
PAINT AQUA (-2850 2325);
DISPLAY INVISIBLE (-2850 2325);
FORCEADD UNIVERSAL_GND..1
(1300 175);
FORCEPROP 3 LASTPIN (1300 225) SIG_NAME GND\g
J 0
(1310 235);
DISPLAY 0.659574 (1310 235);
PAINT MONO (1310 235);
DISPLAY INVISIBLE (1310 235);
FORCEPROP 2 LAST CDS_LIB logical_power
J 0
(1300 175);
PAINT MONO (1300 175);
DISPLAY INVISIBLE (1300 175);
FORCEPROP 1 LAST HDL_POWER GND
J 1
(1325 100);
DISPLAY 0.872340 (1325 100);
PAINT GREEN (1325 100);
DISPLAY INVISIBLE (1325 100);
FORCEPROP 1 LAST PATH I120
J 0
(1375 175);
DISPLAY 0.872340 (1375 175);
PAINT AQUA (1375 175);
DISPLAY INVISIBLE (1375 175);
FORCEADD UNIVERSAL_GND..1
(2925 175);
FORCEPROP 3 LASTPIN (2925 225) SIG_NAME GND\g
J 0
(2935 235);
DISPLAY 0.659574 (2935 235);
PAINT MONO (2935 235);
DISPLAY INVISIBLE (2935 235);
FORCEPROP 2 LAST CDS_LIB logical_power
J 0
(2925 175);
PAINT MONO (2925 175);
DISPLAY INVISIBLE (2925 175);
FORCEPROP 1 LAST HDL_POWER GND
J 1
(2950 100);
DISPLAY 0.872340 (2950 100);
PAINT GREEN (2950 100);
DISPLAY INVISIBLE (2950 100);
FORCEPROP 1 LAST PATH I121
J 0
(3000 175);
DISPLAY 0.872340 (3000 175);
PAINT AQUA (3000 175);
DISPLAY INVISIBLE (3000 175);
FORCEADD Q_CAP..1
(1300 550);
FORCEPROP 1 LAST PART_NUMBER CH5221MEB00
J 0
(1350 400);
DISPLAY 0.978723 (1350 400);
DISPLAY INVISIBLE (1350 400);
FORCEPROP 1 LAST TOLERANCE 20%
J 0
(1350 500);
DISPLAY 0.978723 (1350 500);
FORCEPROP 1 LAST PACK_TYPE C0402
J 0
(1350 350);
DISPLAY 0.978723 (1350 350);
FORCEPROP 1 LAST MATERIAL X6S
J 0
(1350 450);
DISPLAY 0.978723 (1350 450);
FORCEPROP 1 LAST VOLTAGE 6.3V
J 0
(1350 550);
DISPLAY 0.978723 (1350 550);
FORCEPROP 1 LAST VALUE 2.2UF
J 0
(1350 600);
DISPLAY 0.978723 (1350 600);
FORCEPROP 1 LAST $LOCATION C35
J 0
(1350 650);
DISPLAY 0.978723 (1350 650);
FORCEPROP 1 LASTPIN (1300 650) $PN 1
J 0
(1310 630);
DISPLAY 0.787234 (1310 630);
FORCEPROP 1 LASTPIN (1300 450) $PN 2
J 0
(1310 430);
DISPLAY 0.787234 (1310 430);
FORCEPROP 2 LAST CDS_LIB pure_quanta
J 0
(1300 550);
PAINT MONO (1300 550);
DISPLAY INVISIBLE (1300 550);
FORCEPROP 2 LAST CDS_LOCATION C35
J 0
(1350 750);
DISPLAY 1.021277 (1350 750);
DISPLAY INVISIBLE (1350 750);
FORCEPROP 2 LAST $SEC 1
J 0
(1350 750);
DISPLAY 0.680851 (1350 750);
PAINT MONO (1350 750);
DISPLAY INVISIBLE (1350 750);
FORCEPROP 2 LAST CDS_SEC 1
J 0
(1350 750);
DISPLAY 1.021277 (1350 750);
DISPLAY INVISIBLE (1350 750);
FORCEPROP 1 LAST PATH I122
J 0
(1350 700);
DISPLAY 0.978723 (1350 700);
PAINT WHITE (1350 700);
DISPLAY INVISIBLE (1350 700);
FORCEADD VCC_CORE..1
(1300 875);
FORCEPROP 3 LASTPIN (1300 825) SIG_NAME P3V3_AUX\g
J 0
(1310 835);
DISPLAY 0.659574 (1310 835);
PAINT MONO (1310 835);
DISPLAY INVISIBLE (1310 835);
FORCEPROP 1 LAST HDL_POWER P3V3_AUX
J 1
(1300 925);
DISPLAY 1.148936 (1300 925);
PAINT GREEN (1300 925);
FORCEPROP 2 LAST CDS_LIB logical_power
J 0
(1300 875);
PAINT MONO (1300 875);
DISPLAY INVISIBLE (1300 875);
FORCEPROP 1 LAST PATH I123
J 0
(1350 900);
DISPLAY 0.872340 (1350 900);
PAINT AQUA (1350 900);
DISPLAY INVISIBLE (1350 900);
FORCEADD OFFPAGE..3
(400 2800);
FORCEPROP 2 LAST $XR1 92 
J 0
(704 2800);
DISPLAY 0.638298 (704 2800);
PAINT MONO (704 2800);
FORCEPROP 2 LAST $XR0 25 
J 0
(614 2800);
DISPLAY 0.638298 (614 2800);
PAINT MONO (614 2800);
FORCEPROP 2 LAST CDS_LIB standard
J 2
(400 2800);
DISPLAY INVISIBLE (400 2800);
FORCEPROP 1 LAST OFFPAGE TRUE
J 0
(725 2675);
DISPLAY 0.872340 (725 2675);
DISPLAY INVISIBLE (725 2675);
FORCEPROP 1 LAST COMMENT_BODY TRUE
J 0
(350 2700);
DISPLAY 0.872340 (350 2700);
PAINT GREEN (350 2700);
DISPLAY INVISIBLE (350 2700);
FORCEPROP 2 LAST PATH I124
J 0
(600 2875);
DISPLAY 1.021277 (600 2875);
DISPLAY INVISIBLE (600 2875);
FORCEADD Q_CAP..1
(2300 550);
FORCEPROP 1 LAST PART_NUMBER CH6103KEA00
J 0
(2350 400);
DISPLAY 0.978723 (2350 400);
DISPLAY INVISIBLE (2350 400);
FORCEPROP 1 LAST TOLERANCE 10%
J 0
(2350 500);
DISPLAY 0.978723 (2350 500);
FORCEPROP 1 LAST VOLTAGE 16V
J 0
(2350 550);
DISPLAY 0.978723 (2350 550);
FORCEPROP 1 LAST VALUE 10UF
J 0
(2350 600);
DISPLAY 0.978723 (2350 600);
FORCEPROP 1 LAST MATERIAL X6S
J 0
(2350 450);
DISPLAY 0.978723 (2350 450);
FORCEPROP 1 LAST PACK_TYPE C0805
J 0
(2350 350);
DISPLAY 0.978723 (2350 350);
FORCEPROP 1 LAST $LOCATION C36
J 0
(2350 650);
DISPLAY 0.978723 (2350 650);
FORCEPROP 1 LASTPIN (2300 650) $PN 1
J 0
(2310 630);
DISPLAY 0.787234 (2310 630);
FORCEPROP 1 LASTPIN (2300 450) $PN 2
J 0
(2310 430);
DISPLAY 0.787234 (2310 430);
FORCEPROP 2 LAST CDS_LIB pure_quanta
J 0
(2300 550);
PAINT MONO (2300 550);
DISPLAY INVISIBLE (2300 550);
FORCEPROP 2 LAST CDS_LOCATION C36
J 0
(2350 750);
DISPLAY 1.021277 (2350 750);
DISPLAY INVISIBLE (2350 750);
FORCEPROP 2 LAST $SEC 1
J 0
(2350 750);
DISPLAY 0.680851 (2350 750);
PAINT MONO (2350 750);
DISPLAY INVISIBLE (2350 750);
FORCEPROP 2 LAST CDS_SEC 1
J 0
(2350 750);
DISPLAY 1.021277 (2350 750);
DISPLAY INVISIBLE (2350 750);
FORCEPROP 1 LAST PATH I126
J 0
(2350 700);
DISPLAY 0.978723 (2350 700);
PAINT WHITE (2350 700);
DISPLAY INVISIBLE (2350 700);
FORCEADD VCC_CORE..1
(2300 875);
FORCEPROP 3 LASTPIN (2300 825) SIG_NAME P12V_S3_AUX_CPU0_NVDIMM\g
J 0
(2310 835);
DISPLAY 0.659574 (2310 835);
PAINT MONO (2310 835);
DISPLAY INVISIBLE (2310 835);
FORCEPROP 1 LAST HDL_POWER P12V_S3_AUX_CPU0_NVDIMM
J 1
(2300 925);
DISPLAY 1.148936 (2300 925);
PAINT GREEN (2300 925);
FORCEPROP 2 LAST CDS_LIB logical_power
J 0
(2300 875);
PAINT MONO (2300 875);
DISPLAY INVISIBLE (2300 875);
FORCEPROP 1 LAST PATH I127
J 0
(2350 900);
DISPLAY 0.872340 (2350 900);
PAINT AQUA (2350 900);
DISPLAY INVISIBLE (2350 900);
FORCEADD Q_CAP..1
(2925 550);
FORCEPROP 1 LAST PART_NUMBER CH6103KEA00
J 0
(2975 400);
DISPLAY 0.978723 (2975 400);
DISPLAY INVISIBLE (2975 400);
FORCEPROP 1 LAST PACK_TYPE C0805
J 0
(2975 350);
DISPLAY 0.978723 (2975 350);
FORCEPROP 1 LAST VALUE 10UF
J 0
(2975 600);
DISPLAY 0.978723 (2975 600);
FORCEPROP 1 LAST VOLTAGE 16V
J 0
(2975 550);
DISPLAY 0.978723 (2975 550);
FORCEPROP 1 LAST TOLERANCE 10%
J 0
(2975 500);
DISPLAY 0.978723 (2975 500);
FORCEPROP 1 LAST MATERIAL X6S
J 0
(2975 450);
DISPLAY 0.978723 (2975 450);
FORCEPROP 1 LAST $LOCATION C37
J 0
(2975 650);
DISPLAY 0.978723 (2975 650);
FORCEPROP 1 LASTPIN (2925 650) $PN 1
J 0
(2935 630);
DISPLAY 0.787234 (2935 630);
FORCEPROP 1 LASTPIN (2925 450) $PN 2
J 0
(2935 430);
DISPLAY 0.787234 (2935 430);
FORCEPROP 2 LAST CDS_LIB pure_quanta
J 0
(2925 550);
PAINT MONO (2925 550);
DISPLAY INVISIBLE (2925 550);
FORCEPROP 2 LAST CDS_LOCATION C37
J 0
(2975 750);
DISPLAY 1.021277 (2975 750);
DISPLAY INVISIBLE (2975 750);
FORCEPROP 2 LAST $SEC 1
J 0
(2975 750);
DISPLAY 0.680851 (2975 750);
PAINT MONO (2975 750);
DISPLAY INVISIBLE (2975 750);
FORCEPROP 2 LAST CDS_SEC 1
J 0
(2975 750);
DISPLAY 1.021277 (2975 750);
DISPLAY INVISIBLE (2975 750);
FORCEPROP 1 LAST PATH I128
J 0
(2975 700);
DISPLAY 0.978723 (2975 700);
PAINT WHITE (2975 700);
DISPLAY INVISIBLE (2975 700);
FORCEADD TAP..1
(2325 2475);
FORCEPROP 3 LASTPIN (2275 2475) SIG_NAME M_F_CPU0_SB_DQS_DP<0>
J 0
(2285 2485);
DISPLAY 0.659574 (2285 2485);
PAINT MONO (2285 2485);
DISPLAY INVISIBLE (2285 2485);
FORCEPROP 1 LASTPIN (2275 2475) BN 0
J 0
(2263 2483);
DISPLAY 0.680851 (2263 2483);
PAINT GREEN (2263 2483);
FORCEPROP 2 LAST CDS_LIB standard
J 0
(2325 2475);
PAINT MONO (2325 2475);
DISPLAY INVISIBLE (2325 2475);
FORCEPROP 1 LAST BODY_TYPE PLUMBING
J 0
(2325 2525);
DISPLAY 0.872340 (2325 2525);
PAINT GREEN (2325 2525);
DISPLAY INVISIBLE (2325 2525);
FORCEPROP 1 LAST HDL_TAP TRUE
J 0
(2650 2350);
DISPLAY 0.872340 (2650 2350);
DISPLAY INVISIBLE (2650 2350);
FORCEPROP 1 LAST PATH I129
J 0
(2323 2475);
DISPLAY 0.872340 (2323 2475);
PAINT GREEN (2323 2475);
DISPLAY INVISIBLE (2323 2475);
FORCEADD OFFPAGE..3
R 2
(-3000 2600);
FORCEPROP 2 LAST $XR1 92 
J 0
(-3339 2600);
DISPLAY 0.638298 (-3339 2600);
PAINT MONO (-3339 2600);
FORCEPROP 2 LAST $XR0 25 
J 0
(-3249 2600);
DISPLAY 0.638298 (-3249 2600);
PAINT MONO (-3249 2600);
FORCEPROP 2 LAST CDS_LIB standard
J 0
(-3000 2600);
PAINT MONO (-3000 2600);
DISPLAY INVISIBLE (-3000 2600);
FORCEPROP 1 LAST OFFPAGE TRUE
J 2
(-3325 2475);
DISPLAY 0.872340 (-3325 2475);
DISPLAY INVISIBLE (-3325 2475);
FORCEPROP 1 LAST COMMENT_BODY TRUE
J 2
(-2950 2500);
DISPLAY 0.872340 (-2950 2500);
PAINT GREEN (-2950 2500);
DISPLAY INVISIBLE (-2950 2500);
FORCEPROP 2 LAST PATH I13
J 0
(-2950 2675);
DISPLAY 1.021277 (-2950 2675);
DISPLAY INVISIBLE (-2950 2675);
FORCEADD TAP..1
(2325 2575);
FORCEPROP 3 LASTPIN (2275 2575) SIG_NAME M_F_CPU0_SB_DQS_DP<1>
J 0
(2285 2585);
DISPLAY 0.659574 (2285 2585);
PAINT MONO (2285 2585);
DISPLAY INVISIBLE (2285 2585);
FORCEPROP 1 LASTPIN (2275 2575) BN 1
J 0
(2263 2583);
DISPLAY 0.680851 (2263 2583);
PAINT GREEN (2263 2583);
FORCEPROP 2 LAST CDS_LIB standard
J 0
(2325 2575);
DISPLAY INVISIBLE (2325 2575);
FORCEPROP 1 LAST BODY_TYPE PLUMBING
J 0
(2325 2625);
DISPLAY 0.872340 (2325 2625);
PAINT GREEN (2325 2625);
DISPLAY INVISIBLE (2325 2625);
FORCEPROP 1 LAST HDL_TAP TRUE
J 0
(2650 2450);
DISPLAY 0.872340 (2650 2450);
DISPLAY INVISIBLE (2650 2450);
FORCEPROP 1 LAST PATH I130
J 0
(2323 2575);
DISPLAY 0.872340 (2323 2575);
PAINT GREEN (2323 2575);
DISPLAY INVISIBLE (2323 2575);
FORCEADD TAP..1
(2325 2775);
FORCEPROP 3 LASTPIN (2275 2775) SIG_NAME M_F_CPU0_SB_DQS_DP<3>
J 0
(2285 2785);
DISPLAY 0.659574 (2285 2785);
PAINT MONO (2285 2785);
DISPLAY INVISIBLE (2285 2785);
FORCEPROP 1 LASTPIN (2275 2775) BN 3
J 0
(2263 2783);
DISPLAY 0.680851 (2263 2783);
PAINT GREEN (2263 2783);
FORCEPROP 2 LAST CDS_LIB standard
J 0
(2325 2775);
PAINT MONO (2325 2775);
DISPLAY INVISIBLE (2325 2775);
FORCEPROP 1 LAST BODY_TYPE PLUMBING
J 0
(2325 2825);
DISPLAY 0.872340 (2325 2825);
PAINT GREEN (2325 2825);
DISPLAY INVISIBLE (2325 2825);
FORCEPROP 1 LAST HDL_TAP TRUE
J 0
(2650 2650);
DISPLAY 0.872340 (2650 2650);
DISPLAY INVISIBLE (2650 2650);
FORCEPROP 1 LAST PATH I131
J 0
(2323 2775);
DISPLAY 0.872340 (2323 2775);
PAINT GREEN (2323 2775);
DISPLAY INVISIBLE (2323 2775);
FORCEADD TAP..1
(2325 2675);
FORCEPROP 3 LASTPIN (2275 2675) SIG_NAME M_F_CPU0_SB_DQS_DP<2>
J 0
(2285 2685);
DISPLAY 0.659574 (2285 2685);
PAINT MONO (2285 2685);
DISPLAY INVISIBLE (2285 2685);
FORCEPROP 1 LASTPIN (2275 2675) BN 2
J 0
(2263 2683);
DISPLAY 0.680851 (2263 2683);
PAINT GREEN (2263 2683);
FORCEPROP 2 LAST CDS_LIB standard
J 0
(2325 2675);
DISPLAY INVISIBLE (2325 2675);
FORCEPROP 1 LAST BODY_TYPE PLUMBING
J 0
(2325 2725);
DISPLAY 0.872340 (2325 2725);
PAINT GREEN (2325 2725);
DISPLAY INVISIBLE (2325 2725);
FORCEPROP 1 LAST HDL_TAP TRUE
J 0
(2650 2550);
DISPLAY 0.872340 (2650 2550);
DISPLAY INVISIBLE (2650 2550);
FORCEPROP 1 LAST PATH I132
J 0
(2323 2675);
DISPLAY 0.872340 (2323 2675);
PAINT GREEN (2323 2675);
DISPLAY INVISIBLE (2323 2675);
FORCEADD TAP..1
(2325 2875);
FORCEPROP 3 LASTPIN (2275 2875) SIG_NAME M_F_CPU0_SB_DQS_DP<4>
J 0
(2285 2885);
DISPLAY 0.659574 (2285 2885);
PAINT MONO (2285 2885);
DISPLAY INVISIBLE (2285 2885);
FORCEPROP 1 LASTPIN (2275 2875) BN 4
J 0
(2263 2883);
DISPLAY 0.680851 (2263 2883);
PAINT GREEN (2263 2883);
FORCEPROP 2 LAST CDS_LIB standard
J 0
(2325 2875);
PAINT MONO (2325 2875);
DISPLAY INVISIBLE (2325 2875);
FORCEPROP 1 LAST BODY_TYPE PLUMBING
J 0
(2325 2925);
DISPLAY 0.872340 (2325 2925);
PAINT GREEN (2325 2925);
DISPLAY INVISIBLE (2325 2925);
FORCEPROP 1 LAST HDL_TAP TRUE
J 0
(2650 2750);
DISPLAY 0.872340 (2650 2750);
DISPLAY INVISIBLE (2650 2750);
FORCEPROP 1 LAST PATH I133
J 0
(2323 2875);
DISPLAY 0.872340 (2323 2875);
PAINT GREEN (2323 2875);
DISPLAY INVISIBLE (2323 2875);
FORCEADD TAP..1
(2325 2975);
FORCEPROP 3 LASTPIN (2275 2975) SIG_NAME M_F_CPU0_SB_DQS_DP<5>
J 0
(2285 2985);
DISPLAY 0.659574 (2285 2985);
PAINT MONO (2285 2985);
DISPLAY INVISIBLE (2285 2985);
FORCEPROP 1 LASTPIN (2275 2975) BN 5
J 0
(2263 2983);
DISPLAY 0.680851 (2263 2983);
PAINT GREEN (2263 2983);
FORCEPROP 2 LAST CDS_LIB standard
J 0
(2325 2975);
DISPLAY INVISIBLE (2325 2975);
FORCEPROP 1 LAST BODY_TYPE PLUMBING
J 0
(2325 3025);
DISPLAY 0.872340 (2325 3025);
PAINT GREEN (2325 3025);
DISPLAY INVISIBLE (2325 3025);
FORCEPROP 1 LAST HDL_TAP TRUE
J 0
(2650 2850);
DISPLAY 0.872340 (2650 2850);
DISPLAY INVISIBLE (2650 2850);
FORCEPROP 1 LAST PATH I134
J 0
(2323 2975);
DISPLAY 0.872340 (2323 2975);
PAINT GREEN (2323 2975);
DISPLAY INVISIBLE (2323 2975);
FORCEADD TAP..1
(2325 3075);
FORCEPROP 3 LASTPIN (2275 3075) SIG_NAME M_F_CPU0_SB_DQS_DP<6>
J 0
(2285 3085);
DISPLAY 0.659574 (2285 3085);
PAINT MONO (2285 3085);
DISPLAY INVISIBLE (2285 3085);
FORCEPROP 1 LASTPIN (2275 3075) BN 6
J 0
(2263 3083);
DISPLAY 0.680851 (2263 3083);
PAINT GREEN (2263 3083);
FORCEPROP 2 LAST CDS_LIB standard
J 0
(2325 3075);
DISPLAY INVISIBLE (2325 3075);
FORCEPROP 1 LAST BODY_TYPE PLUMBING
J 0
(2325 3125);
DISPLAY 0.872340 (2325 3125);
PAINT GREEN (2325 3125);
DISPLAY INVISIBLE (2325 3125);
FORCEPROP 1 LAST HDL_TAP TRUE
J 0
(2650 2950);
DISPLAY 0.872340 (2650 2950);
DISPLAY INVISIBLE (2650 2950);
FORCEPROP 1 LAST PATH I135
J 0
(2323 3075);
DISPLAY 0.872340 (2323 3075);
PAINT GREEN (2323 3075);
DISPLAY INVISIBLE (2323 3075);
FORCEADD TAP..1
(2325 3175);
FORCEPROP 3 LASTPIN (2275 3175) SIG_NAME M_F_CPU0_SB_DQS_DP<7>
J 0
(2285 3185);
DISPLAY 0.659574 (2285 3185);
PAINT MONO (2285 3185);
DISPLAY INVISIBLE (2285 3185);
FORCEPROP 1 LASTPIN (2275 3175) BN 7
J 0
(2263 3183);
DISPLAY 0.680851 (2263 3183);
PAINT GREEN (2263 3183);
FORCEPROP 2 LAST CDS_LIB standard
J 0
(2325 3175);
DISPLAY INVISIBLE (2325 3175);
FORCEPROP 1 LAST BODY_TYPE PLUMBING
J 0
(2325 3225);
DISPLAY 0.872340 (2325 3225);
PAINT GREEN (2325 3225);
DISPLAY INVISIBLE (2325 3225);
FORCEPROP 1 LAST HDL_TAP TRUE
J 0
(2650 3050);
DISPLAY 0.872340 (2650 3050);
DISPLAY INVISIBLE (2650 3050);
FORCEPROP 1 LAST PATH I136
J 0
(2323 3175);
DISPLAY 0.872340 (2323 3175);
PAINT GREEN (2323 3175);
DISPLAY INVISIBLE (2323 3175);
FORCEADD TAP..1
(2325 3275);
FORCEPROP 3 LASTPIN (2275 3275) SIG_NAME M_F_CPU0_SB_DQS_DP<8>
J 0
(2285 3285);
DISPLAY 0.659574 (2285 3285);
PAINT MONO (2285 3285);
DISPLAY INVISIBLE (2285 3285);
FORCEPROP 1 LASTPIN (2275 3275) BN 8
J 0
(2263 3283);
DISPLAY 0.680851 (2263 3283);
PAINT GREEN (2263 3283);
FORCEPROP 2 LAST CDS_LIB standard
J 0
(2325 3275);
DISPLAY INVISIBLE (2325 3275);
FORCEPROP 1 LAST BODY_TYPE PLUMBING
J 0
(2325 3325);
DISPLAY 0.872340 (2325 3325);
PAINT GREEN (2325 3325);
DISPLAY INVISIBLE (2325 3325);
FORCEPROP 1 LAST HDL_TAP TRUE
J 0
(2650 3150);
DISPLAY 0.872340 (2650 3150);
DISPLAY INVISIBLE (2650 3150);
FORCEPROP 1 LAST PATH I137
J 0
(2323 3275);
DISPLAY 0.872340 (2323 3275);
PAINT GREEN (2323 3275);
DISPLAY INVISIBLE (2323 3275);
FORCEADD TAP..1
(2500 2425);
FORCEPROP 3 LASTPIN (2450 2425) SIG_NAME M_F_CPU0_SB_DQS_DN<0>
J 0
(2460 2435);
DISPLAY 0.659574 (2460 2435);
PAINT MONO (2460 2435);
DISPLAY INVISIBLE (2460 2435);
FORCEPROP 1 LASTPIN (2450 2425) BN 0
J 0
(2438 2433);
DISPLAY 0.680851 (2438 2433);
PAINT GREEN (2438 2433);
FORCEPROP 2 LAST CDS_LIB standard
J 0
(2500 2425);
PAINT MONO (2500 2425);
DISPLAY INVISIBLE (2500 2425);
FORCEPROP 1 LAST BODY_TYPE PLUMBING
J 0
(2500 2475);
DISPLAY 0.872340 (2500 2475);
PAINT GREEN (2500 2475);
DISPLAY INVISIBLE (2500 2475);
FORCEPROP 1 LAST HDL_TAP TRUE
J 0
(2825 2300);
DISPLAY 0.872340 (2825 2300);
DISPLAY INVISIBLE (2825 2300);
FORCEPROP 1 LAST PATH I138
J 0
(2498 2425);
DISPLAY 0.872340 (2498 2425);
PAINT GREEN (2498 2425);
DISPLAY INVISIBLE (2498 2425);
FORCEADD TAP..1
(2500 2525);
FORCEPROP 3 LASTPIN (2450 2525) SIG_NAME M_F_CPU0_SB_DQS_DN<1>
J 0
(2460 2535);
DISPLAY 0.659574 (2460 2535);
PAINT MONO (2460 2535);
DISPLAY INVISIBLE (2460 2535);
FORCEPROP 1 LASTPIN (2450 2525) BN 1
J 0
(2438 2533);
DISPLAY 0.680851 (2438 2533);
PAINT GREEN (2438 2533);
FORCEPROP 2 LAST CDS_LIB standard
J 0
(2500 2525);
DISPLAY INVISIBLE (2500 2525);
FORCEPROP 1 LAST BODY_TYPE PLUMBING
J 0
(2500 2575);
DISPLAY 0.872340 (2500 2575);
PAINT GREEN (2500 2575);
DISPLAY INVISIBLE (2500 2575);
FORCEPROP 1 LAST HDL_TAP TRUE
J 0
(2825 2400);
DISPLAY 0.872340 (2825 2400);
DISPLAY INVISIBLE (2825 2400);
FORCEPROP 1 LAST PATH I139
J 0
(2498 2525);
DISPLAY 0.872340 (2498 2525);
PAINT GREEN (2498 2525);
DISPLAY INVISIBLE (2498 2525);
FORCEADD OFFPAGE..3
R 2
(-3000 3050);
FORCEPROP 2 LAST $XR1 92 
J 0
(-3339 3050);
DISPLAY 0.638298 (-3339 3050);
PAINT MONO (-3339 3050);
FORCEPROP 2 LAST $XR0 25 
J 0
(-3249 3050);
DISPLAY 0.638298 (-3249 3050);
PAINT MONO (-3249 3050);
FORCEPROP 2 LAST CDS_LIB standard
J 0
(-3000 3050);
PAINT MONO (-3000 3050);
DISPLAY INVISIBLE (-3000 3050);
FORCEPROP 1 LAST OFFPAGE TRUE
J 2
(-3325 2925);
DISPLAY 0.872340 (-3325 2925);
DISPLAY INVISIBLE (-3325 2925);
FORCEPROP 1 LAST COMMENT_BODY TRUE
J 2
(-2950 2950);
DISPLAY 0.872340 (-2950 2950);
PAINT GREEN (-2950 2950);
DISPLAY INVISIBLE (-2950 2950);
FORCEPROP 2 LAST PATH I14
J 0
(-2950 3125);
DISPLAY 1.021277 (-2950 3125);
DISPLAY INVISIBLE (-2950 3125);
FORCEADD TAP..1
(2500 2725);
FORCEPROP 3 LASTPIN (2450 2725) SIG_NAME M_F_CPU0_SB_DQS_DN<3>
J 0
(2460 2735);
DISPLAY 0.659574 (2460 2735);
PAINT MONO (2460 2735);
DISPLAY INVISIBLE (2460 2735);
FORCEPROP 1 LASTPIN (2450 2725) BN 3
J 0
(2438 2733);
DISPLAY 0.680851 (2438 2733);
PAINT GREEN (2438 2733);
FORCEPROP 2 LAST CDS_LIB standard
J 0
(2500 2725);
PAINT MONO (2500 2725);
DISPLAY INVISIBLE (2500 2725);
FORCEPROP 1 LAST BODY_TYPE PLUMBING
J 0
(2500 2775);
DISPLAY 0.872340 (2500 2775);
PAINT GREEN (2500 2775);
DISPLAY INVISIBLE (2500 2775);
FORCEPROP 1 LAST HDL_TAP TRUE
J 0
(2825 2600);
DISPLAY 0.872340 (2825 2600);
DISPLAY INVISIBLE (2825 2600);
FORCEPROP 1 LAST PATH I140
J 0
(2498 2725);
DISPLAY 0.872340 (2498 2725);
PAINT GREEN (2498 2725);
DISPLAY INVISIBLE (2498 2725);
FORCEADD TAP..1
(2500 2625);
FORCEPROP 3 LASTPIN (2450 2625) SIG_NAME M_F_CPU0_SB_DQS_DN<2>
J 0
(2460 2635);
DISPLAY 0.659574 (2460 2635);
PAINT MONO (2460 2635);
DISPLAY INVISIBLE (2460 2635);
FORCEPROP 1 LASTPIN (2450 2625) BN 2
J 0
(2438 2633);
DISPLAY 0.680851 (2438 2633);
PAINT GREEN (2438 2633);
FORCEPROP 2 LAST CDS_LIB standard
J 0
(2500 2625);
DISPLAY INVISIBLE (2500 2625);
FORCEPROP 1 LAST BODY_TYPE PLUMBING
J 0
(2500 2675);
DISPLAY 0.872340 (2500 2675);
PAINT GREEN (2500 2675);
DISPLAY INVISIBLE (2500 2675);
FORCEPROP 1 LAST HDL_TAP TRUE
J 0
(2825 2500);
DISPLAY 0.872340 (2825 2500);
DISPLAY INVISIBLE (2825 2500);
FORCEPROP 1 LAST PATH I141
J 0
(2498 2625);
DISPLAY 0.872340 (2498 2625);
PAINT GREEN (2498 2625);
DISPLAY INVISIBLE (2498 2625);
FORCEADD TAP..1
(2500 2825);
FORCEPROP 3 LASTPIN (2450 2825) SIG_NAME M_F_CPU0_SB_DQS_DN<4>
J 0
(2460 2835);
DISPLAY 0.659574 (2460 2835);
PAINT MONO (2460 2835);
DISPLAY INVISIBLE (2460 2835);
FORCEPROP 1 LASTPIN (2450 2825) BN 4
J 0
(2438 2833);
DISPLAY 0.680851 (2438 2833);
PAINT GREEN (2438 2833);
FORCEPROP 2 LAST CDS_LIB standard
J 0
(2500 2825);
PAINT MONO (2500 2825);
DISPLAY INVISIBLE (2500 2825);
FORCEPROP 1 LAST BODY_TYPE PLUMBING
J 0
(2500 2875);
DISPLAY 0.872340 (2500 2875);
PAINT GREEN (2500 2875);
DISPLAY INVISIBLE (2500 2875);
FORCEPROP 1 LAST HDL_TAP TRUE
J 0
(2825 2700);
DISPLAY 0.872340 (2825 2700);
DISPLAY INVISIBLE (2825 2700);
FORCEPROP 1 LAST PATH I142
J 0
(2498 2825);
DISPLAY 0.872340 (2498 2825);
PAINT GREEN (2498 2825);
DISPLAY INVISIBLE (2498 2825);
FORCEADD TAP..1
(2500 2925);
FORCEPROP 3 LASTPIN (2450 2925) SIG_NAME M_F_CPU0_SB_DQS_DN<5>
J 0
(2460 2935);
DISPLAY 0.659574 (2460 2935);
PAINT MONO (2460 2935);
DISPLAY INVISIBLE (2460 2935);
FORCEPROP 1 LASTPIN (2450 2925) BN 5
J 0
(2438 2933);
DISPLAY 0.680851 (2438 2933);
PAINT GREEN (2438 2933);
FORCEPROP 2 LAST CDS_LIB standard
J 0
(2500 2925);
DISPLAY INVISIBLE (2500 2925);
FORCEPROP 1 LAST BODY_TYPE PLUMBING
J 0
(2500 2975);
DISPLAY 0.872340 (2500 2975);
PAINT GREEN (2500 2975);
DISPLAY INVISIBLE (2500 2975);
FORCEPROP 1 LAST HDL_TAP TRUE
J 0
(2825 2800);
DISPLAY 0.872340 (2825 2800);
DISPLAY INVISIBLE (2825 2800);
FORCEPROP 1 LAST PATH I143
J 0
(2498 2925);
DISPLAY 0.872340 (2498 2925);
PAINT GREEN (2498 2925);
DISPLAY INVISIBLE (2498 2925);
FORCEADD TAP..1
(2500 3025);
FORCEPROP 3 LASTPIN (2450 3025) SIG_NAME M_F_CPU0_SB_DQS_DN<6>
J 0
(2460 3035);
DISPLAY 0.659574 (2460 3035);
PAINT MONO (2460 3035);
DISPLAY INVISIBLE (2460 3035);
FORCEPROP 1 LASTPIN (2450 3025) BN 6
J 0
(2438 3033);
DISPLAY 0.680851 (2438 3033);
PAINT GREEN (2438 3033);
FORCEPROP 2 LAST CDS_LIB standard
J 0
(2500 3025);
DISPLAY INVISIBLE (2500 3025);
FORCEPROP 1 LAST BODY_TYPE PLUMBING
J 0
(2500 3075);
DISPLAY 0.872340 (2500 3075);
PAINT GREEN (2500 3075);
DISPLAY INVISIBLE (2500 3075);
FORCEPROP 1 LAST HDL_TAP TRUE
J 0
(2825 2900);
DISPLAY 0.872340 (2825 2900);
DISPLAY INVISIBLE (2825 2900);
FORCEPROP 1 LAST PATH I144
J 0
(2498 3025);
DISPLAY 0.872340 (2498 3025);
PAINT GREEN (2498 3025);
DISPLAY INVISIBLE (2498 3025);
FORCEADD TAP..1
(2500 3225);
FORCEPROP 3 LASTPIN (2450 3225) SIG_NAME M_F_CPU0_SB_DQS_DN<8>
J 0
(2460 3235);
DISPLAY 0.659574 (2460 3235);
PAINT MONO (2460 3235);
DISPLAY INVISIBLE (2460 3235);
FORCEPROP 1 LASTPIN (2450 3225) BN 8
J 0
(2438 3233);
DISPLAY 0.680851 (2438 3233);
PAINT GREEN (2438 3233);
FORCEPROP 2 LAST CDS_LIB standard
J 0
(2500 3225);
DISPLAY INVISIBLE (2500 3225);
FORCEPROP 1 LAST BODY_TYPE PLUMBING
J 0
(2500 3275);
DISPLAY 0.872340 (2500 3275);
PAINT GREEN (2500 3275);
DISPLAY INVISIBLE (2500 3275);
FORCEPROP 1 LAST HDL_TAP TRUE
J 0
(2825 3100);
DISPLAY 0.872340 (2825 3100);
DISPLAY INVISIBLE (2825 3100);
FORCEPROP 1 LAST PATH I145
J 0
(2498 3225);
DISPLAY 0.872340 (2498 3225);
PAINT GREEN (2498 3225);
DISPLAY INVISIBLE (2498 3225);
FORCEADD TAP..1
(2500 3125);
FORCEPROP 3 LASTPIN (2450 3125) SIG_NAME M_F_CPU0_SB_DQS_DN<7>
J 0
(2460 3135);
DISPLAY 0.659574 (2460 3135);
PAINT MONO (2460 3135);
DISPLAY INVISIBLE (2460 3135);
FORCEPROP 1 LASTPIN (2450 3125) BN 7
J 0
(2438 3133);
DISPLAY 0.680851 (2438 3133);
PAINT GREEN (2438 3133);
FORCEPROP 2 LAST CDS_LIB standard
J 0
(2500 3125);
DISPLAY INVISIBLE (2500 3125);
FORCEPROP 1 LAST BODY_TYPE PLUMBING
J 0
(2500 3175);
DISPLAY 0.872340 (2500 3175);
PAINT GREEN (2500 3175);
DISPLAY INVISIBLE (2500 3175);
FORCEPROP 1 LAST HDL_TAP TRUE
J 0
(2825 3000);
DISPLAY 0.872340 (2825 3000);
DISPLAY INVISIBLE (2825 3000);
FORCEPROP 1 LAST PATH I146
J 0
(2498 3125);
DISPLAY 0.872340 (2498 3125);
PAINT GREEN (2498 3125);
DISPLAY INVISIBLE (2498 3125);
FORCEADD TAP..1
(2500 3325);
FORCEPROP 3 LASTPIN (2450 3325) SIG_NAME M_F_CPU0_SB_DQS_DN<9>
J 0
(2460 3335);
DISPLAY 0.659574 (2460 3335);
PAINT MONO (2460 3335);
DISPLAY INVISIBLE (2460 3335);
FORCEPROP 1 LASTPIN (2450 3325) BN 9
J 0
(2438 3333);
DISPLAY 0.680851 (2438 3333);
PAINT GREEN (2438 3333);
FORCEPROP 2 LAST CDS_LIB standard
J 0
(2500 3325);
DISPLAY INVISIBLE (2500 3325);
FORCEPROP 1 LAST BODY_TYPE PLUMBING
J 0
(2500 3375);
DISPLAY 0.872340 (2500 3375);
PAINT GREEN (2500 3375);
DISPLAY INVISIBLE (2500 3375);
FORCEPROP 1 LAST HDL_TAP TRUE
J 0
(2825 3200);
DISPLAY 0.872340 (2825 3200);
DISPLAY INVISIBLE (2825 3200);
FORCEPROP 1 LAST PATH I147
J 0
(2498 3325);
DISPLAY 0.872340 (2498 3325);
PAINT GREEN (2498 3325);
DISPLAY INVISIBLE (2498 3325);
FORCEADD TAP..1
(2325 3525);
FORCEPROP 3 LASTPIN (2275 3525) SIG_NAME M_F_CPU0_SA_DQS_DP<0>
J 0
(2285 3535);
DISPLAY 0.659574 (2285 3535);
PAINT MONO (2285 3535);
DISPLAY INVISIBLE (2285 3535);
FORCEPROP 1 LASTPIN (2275 3525) BN 0
J 0
(2263 3533);
DISPLAY 0.680851 (2263 3533);
PAINT GREEN (2263 3533);
FORCEPROP 2 LAST CDS_LIB standard
J 0
(2325 3525);
PAINT MONO (2325 3525);
DISPLAY INVISIBLE (2325 3525);
FORCEPROP 1 LAST BODY_TYPE PLUMBING
J 0
(2325 3575);
DISPLAY 0.872340 (2325 3575);
PAINT GREEN (2325 3575);
DISPLAY INVISIBLE (2325 3575);
FORCEPROP 1 LAST HDL_TAP TRUE
J 0
(2650 3400);
DISPLAY 0.872340 (2650 3400);
DISPLAY INVISIBLE (2650 3400);
FORCEPROP 1 LAST PATH I148
J 0
(2323 3525);
DISPLAY 0.872340 (2323 3525);
PAINT GREEN (2323 3525);
DISPLAY INVISIBLE (2323 3525);
FORCEADD TAP..1
(2325 3375);
FORCEPROP 3 LASTPIN (2275 3375) SIG_NAME M_F_CPU0_SB_DQS_DP<9>
J 0
(2285 3385);
DISPLAY 0.659574 (2285 3385);
PAINT MONO (2285 3385);
DISPLAY INVISIBLE (2285 3385);
FORCEPROP 1 LASTPIN (2275 3375) BN 9
J 0
(2263 3383);
DISPLAY 0.680851 (2263 3383);
PAINT GREEN (2263 3383);
FORCEPROP 2 LAST CDS_LIB standard
J 0
(2325 3375);
DISPLAY INVISIBLE (2325 3375);
FORCEPROP 1 LAST BODY_TYPE PLUMBING
J 0
(2325 3425);
DISPLAY 0.872340 (2325 3425);
PAINT GREEN (2325 3425);
DISPLAY INVISIBLE (2325 3425);
FORCEPROP 1 LAST HDL_TAP TRUE
J 0
(2650 3250);
DISPLAY 0.872340 (2650 3250);
DISPLAY INVISIBLE (2650 3250);
FORCEPROP 1 LAST PATH I149
J 0
(2323 3375);
DISPLAY 0.872340 (2323 3375);
PAINT GREEN (2323 3375);
DISPLAY INVISIBLE (2323 3375);
FORCEADD OFFPAGE..1
(-3000 3125);
FORCEPROP 2 LAST $XR0 25 
J 0
(-3221 3125);
DISPLAY 0.638298 (-3221 3125);
PAINT MONO (-3221 3125);
FORCEPROP 2 LAST CDS_LIB standard
J 0
(-3000 3125);
PAINT MONO (-3000 3125);
DISPLAY INVISIBLE (-3000 3125);
FORCEPROP 1 LAST OFFPAGE TRUE
J 0
(-2675 3000);
DISPLAY 0.872340 (-2675 3000);
DISPLAY INVISIBLE (-2675 3000);
FORCEPROP 1 LAST COMMENT_BODY TRUE
J 0
(-2875 3025);
DISPLAY 0.872340 (-2875 3025);
PAINT GREEN (-2875 3025);
DISPLAY INVISIBLE (-2875 3025);
FORCEPROP 2 LAST PATH I15
J 0
(-2950 3200);
DISPLAY 1.021277 (-2950 3200);
DISPLAY INVISIBLE (-2950 3200);
FORCEADD TAP..1
(2325 3625);
FORCEPROP 3 LASTPIN (2275 3625) SIG_NAME M_F_CPU0_SA_DQS_DP<1>
J 0
(2285 3635);
DISPLAY 0.659574 (2285 3635);
PAINT MONO (2285 3635);
DISPLAY INVISIBLE (2285 3635);
FORCEPROP 1 LASTPIN (2275 3625) BN 1
J 0
(2263 3633);
DISPLAY 0.680851 (2263 3633);
PAINT GREEN (2263 3633);
FORCEPROP 2 LAST CDS_LIB standard
J 0
(2325 3625);
DISPLAY INVISIBLE (2325 3625);
FORCEPROP 1 LAST BODY_TYPE PLUMBING
J 0
(2325 3675);
DISPLAY 0.872340 (2325 3675);
PAINT GREEN (2325 3675);
DISPLAY INVISIBLE (2325 3675);
FORCEPROP 1 LAST HDL_TAP TRUE
J 0
(2650 3500);
DISPLAY 0.872340 (2650 3500);
DISPLAY INVISIBLE (2650 3500);
FORCEPROP 1 LAST PATH I150
J 0
(2323 3625);
DISPLAY 0.872340 (2323 3625);
PAINT GREEN (2323 3625);
DISPLAY INVISIBLE (2323 3625);
FORCEADD TAP..1
(2325 3825);
FORCEPROP 3 LASTPIN (2275 3825) SIG_NAME M_F_CPU0_SA_DQS_DP<3>
J 0
(2285 3835);
DISPLAY 0.659574 (2285 3835);
PAINT MONO (2285 3835);
DISPLAY INVISIBLE (2285 3835);
FORCEPROP 1 LASTPIN (2275 3825) BN 3
J 0
(2263 3833);
DISPLAY 0.680851 (2263 3833);
PAINT GREEN (2263 3833);
FORCEPROP 2 LAST CDS_LIB standard
J 0
(2325 3825);
PAINT MONO (2325 3825);
DISPLAY INVISIBLE (2325 3825);
FORCEPROP 1 LAST BODY_TYPE PLUMBING
J 0
(2325 3875);
DISPLAY 0.872340 (2325 3875);
PAINT GREEN (2325 3875);
DISPLAY INVISIBLE (2325 3875);
FORCEPROP 1 LAST HDL_TAP TRUE
J 0
(2650 3700);
DISPLAY 0.872340 (2650 3700);
DISPLAY INVISIBLE (2650 3700);
FORCEPROP 1 LAST PATH I151
J 0
(2323 3825);
DISPLAY 0.872340 (2323 3825);
PAINT GREEN (2323 3825);
DISPLAY INVISIBLE (2323 3825);
FORCEADD TAP..1
(2325 3725);
FORCEPROP 3 LASTPIN (2275 3725) SIG_NAME M_F_CPU0_SA_DQS_DP<2>
J 0
(2285 3735);
DISPLAY 0.659574 (2285 3735);
PAINT MONO (2285 3735);
DISPLAY INVISIBLE (2285 3735);
FORCEPROP 1 LASTPIN (2275 3725) BN 2
J 0
(2263 3733);
DISPLAY 0.680851 (2263 3733);
PAINT GREEN (2263 3733);
FORCEPROP 2 LAST CDS_LIB standard
J 0
(2325 3725);
DISPLAY INVISIBLE (2325 3725);
FORCEPROP 1 LAST BODY_TYPE PLUMBING
J 0
(2325 3775);
DISPLAY 0.872340 (2325 3775);
PAINT GREEN (2325 3775);
DISPLAY INVISIBLE (2325 3775);
FORCEPROP 1 LAST HDL_TAP TRUE
J 0
(2650 3600);
DISPLAY 0.872340 (2650 3600);
DISPLAY INVISIBLE (2650 3600);
FORCEPROP 1 LAST PATH I152
J 0
(2323 3725);
DISPLAY 0.872340 (2323 3725);
PAINT GREEN (2323 3725);
DISPLAY INVISIBLE (2323 3725);
FORCEADD TAP..1
(2325 3925);
FORCEPROP 3 LASTPIN (2275 3925) SIG_NAME M_F_CPU0_SA_DQS_DP<4>
J 0
(2285 3935);
DISPLAY 0.659574 (2285 3935);
PAINT MONO (2285 3935);
DISPLAY INVISIBLE (2285 3935);
FORCEPROP 1 LASTPIN (2275 3925) BN 4
J 0
(2263 3933);
DISPLAY 0.680851 (2263 3933);
PAINT GREEN (2263 3933);
FORCEPROP 2 LAST CDS_LIB standard
J 0
(2325 3925);
PAINT MONO (2325 3925);
DISPLAY INVISIBLE (2325 3925);
FORCEPROP 1 LAST BODY_TYPE PLUMBING
J 0
(2325 3975);
DISPLAY 0.872340 (2325 3975);
PAINT GREEN (2325 3975);
DISPLAY INVISIBLE (2325 3975);
FORCEPROP 1 LAST HDL_TAP TRUE
J 0
(2650 3800);
DISPLAY 0.872340 (2650 3800);
DISPLAY INVISIBLE (2650 3800);
FORCEPROP 1 LAST PATH I153
J 0
(2323 3925);
DISPLAY 0.872340 (2323 3925);
PAINT GREEN (2323 3925);
DISPLAY INVISIBLE (2323 3925);
FORCEADD TAP..1
(2325 4025);
FORCEPROP 3 LASTPIN (2275 4025) SIG_NAME M_F_CPU0_SA_DQS_DP<5>
J 0
(2285 4035);
DISPLAY 0.659574 (2285 4035);
PAINT MONO (2285 4035);
DISPLAY INVISIBLE (2285 4035);
FORCEPROP 1 LASTPIN (2275 4025) BN 5
J 0
(2263 4033);
DISPLAY 0.680851 (2263 4033);
PAINT GREEN (2263 4033);
FORCEPROP 2 LAST CDS_LIB standard
J 0
(2325 4025);
DISPLAY INVISIBLE (2325 4025);
FORCEPROP 1 LAST BODY_TYPE PLUMBING
J 0
(2325 4075);
DISPLAY 0.872340 (2325 4075);
PAINT GREEN (2325 4075);
DISPLAY INVISIBLE (2325 4075);
FORCEPROP 1 LAST HDL_TAP TRUE
J 0
(2650 3900);
DISPLAY 0.872340 (2650 3900);
DISPLAY INVISIBLE (2650 3900);
FORCEPROP 1 LAST PATH I154
J 0
(2323 4025);
DISPLAY 0.872340 (2323 4025);
PAINT GREEN (2323 4025);
DISPLAY INVISIBLE (2323 4025);
FORCEADD TAP..1
(2325 4125);
FORCEPROP 3 LASTPIN (2275 4125) SIG_NAME M_F_CPU0_SA_DQS_DP<6>
J 0
(2285 4135);
DISPLAY 0.659574 (2285 4135);
PAINT MONO (2285 4135);
DISPLAY INVISIBLE (2285 4135);
FORCEPROP 1 LASTPIN (2275 4125) BN 6
J 0
(2263 4133);
DISPLAY 0.680851 (2263 4133);
PAINT GREEN (2263 4133);
FORCEPROP 2 LAST CDS_LIB standard
J 0
(2325 4125);
DISPLAY INVISIBLE (2325 4125);
FORCEPROP 1 LAST BODY_TYPE PLUMBING
J 0
(2325 4175);
DISPLAY 0.872340 (2325 4175);
PAINT GREEN (2325 4175);
DISPLAY INVISIBLE (2325 4175);
FORCEPROP 1 LAST HDL_TAP TRUE
J 0
(2650 4000);
DISPLAY 0.872340 (2650 4000);
DISPLAY INVISIBLE (2650 4000);
FORCEPROP 1 LAST PATH I155
J 0
(2323 4125);
DISPLAY 0.872340 (2323 4125);
PAINT GREEN (2323 4125);
DISPLAY INVISIBLE (2323 4125);
FORCEADD TAP..1
(2325 4325);
FORCEPROP 3 LASTPIN (2275 4325) SIG_NAME M_F_CPU0_SA_DQS_DP<8>
J 0
(2285 4335);
DISPLAY 0.659574 (2285 4335);
PAINT MONO (2285 4335);
DISPLAY INVISIBLE (2285 4335);
FORCEPROP 1 LASTPIN (2275 4325) BN 8
J 0
(2263 4333);
DISPLAY 0.680851 (2263 4333);
PAINT GREEN (2263 4333);
FORCEPROP 2 LAST CDS_LIB standard
J 0
(2325 4325);
DISPLAY INVISIBLE (2325 4325);
FORCEPROP 1 LAST BODY_TYPE PLUMBING
J 0
(2325 4375);
DISPLAY 0.872340 (2325 4375);
PAINT GREEN (2325 4375);
DISPLAY INVISIBLE (2325 4375);
FORCEPROP 1 LAST HDL_TAP TRUE
J 0
(2650 4200);
DISPLAY 0.872340 (2650 4200);
DISPLAY INVISIBLE (2650 4200);
FORCEPROP 1 LAST PATH I156
J 0
(2323 4325);
DISPLAY 0.872340 (2323 4325);
PAINT GREEN (2323 4325);
DISPLAY INVISIBLE (2323 4325);
FORCEADD TAP..1
(2325 4225);
FORCEPROP 3 LASTPIN (2275 4225) SIG_NAME M_F_CPU0_SA_DQS_DP<7>
J 0
(2285 4235);
DISPLAY 0.659574 (2285 4235);
PAINT MONO (2285 4235);
DISPLAY INVISIBLE (2285 4235);
FORCEPROP 1 LASTPIN (2275 4225) BN 7
J 0
(2263 4233);
DISPLAY 0.680851 (2263 4233);
PAINT GREEN (2263 4233);
FORCEPROP 2 LAST CDS_LIB standard
J 0
(2325 4225);
DISPLAY INVISIBLE (2325 4225);
FORCEPROP 1 LAST BODY_TYPE PLUMBING
J 0
(2325 4275);
DISPLAY 0.872340 (2325 4275);
PAINT GREEN (2325 4275);
DISPLAY INVISIBLE (2325 4275);
FORCEPROP 1 LAST HDL_TAP TRUE
J 0
(2650 4100);
DISPLAY 0.872340 (2650 4100);
DISPLAY INVISIBLE (2650 4100);
FORCEPROP 1 LAST PATH I157
J 0
(2323 4225);
DISPLAY 0.872340 (2323 4225);
PAINT GREEN (2323 4225);
DISPLAY INVISIBLE (2323 4225);
FORCEADD TAP..1
(2500 3475);
FORCEPROP 3 LASTPIN (2450 3475) SIG_NAME M_F_CPU0_SA_DQS_DN<0>
J 0
(2460 3485);
DISPLAY 0.659574 (2460 3485);
PAINT MONO (2460 3485);
DISPLAY INVISIBLE (2460 3485);
FORCEPROP 1 LASTPIN (2450 3475) BN 0
J 0
(2438 3483);
DISPLAY 0.680851 (2438 3483);
PAINT GREEN (2438 3483);
FORCEPROP 2 LAST CDS_LIB standard
J 0
(2500 3475);
PAINT MONO (2500 3475);
DISPLAY INVISIBLE (2500 3475);
FORCEPROP 1 LAST BODY_TYPE PLUMBING
J 0
(2500 3525);
DISPLAY 0.872340 (2500 3525);
PAINT GREEN (2500 3525);
DISPLAY INVISIBLE (2500 3525);
FORCEPROP 1 LAST HDL_TAP TRUE
J 0
(2825 3350);
DISPLAY 0.872340 (2825 3350);
DISPLAY INVISIBLE (2825 3350);
FORCEPROP 1 LAST PATH I158
J 0
(2498 3475);
DISPLAY 0.872340 (2498 3475);
PAINT GREEN (2498 3475);
DISPLAY INVISIBLE (2498 3475);
FORCEADD TAP..1
(2500 3575);
FORCEPROP 3 LASTPIN (2450 3575) SIG_NAME M_F_CPU0_SA_DQS_DN<1>
J 0
(2460 3585);
DISPLAY 0.659574 (2460 3585);
PAINT MONO (2460 3585);
DISPLAY INVISIBLE (2460 3585);
FORCEPROP 1 LASTPIN (2450 3575) BN 1
J 0
(2438 3583);
DISPLAY 0.680851 (2438 3583);
PAINT GREEN (2438 3583);
FORCEPROP 2 LAST CDS_LIB standard
J 0
(2500 3575);
DISPLAY INVISIBLE (2500 3575);
FORCEPROP 1 LAST BODY_TYPE PLUMBING
J 0
(2500 3625);
DISPLAY 0.872340 (2500 3625);
PAINT GREEN (2500 3625);
DISPLAY INVISIBLE (2500 3625);
FORCEPROP 1 LAST HDL_TAP TRUE
J 0
(2825 3450);
DISPLAY 0.872340 (2825 3450);
DISPLAY INVISIBLE (2825 3450);
FORCEPROP 1 LAST PATH I159
J 0
(2498 3575);
DISPLAY 0.872340 (2498 3575);
PAINT GREEN (2498 3575);
DISPLAY INVISIBLE (2498 3575);
FORCEADD OFFPAGE..1
(-3000 3275);
FORCEPROP 2 LAST $XR0 25 
J 0
(-3221 3275);
DISPLAY 0.638298 (-3221 3275);
PAINT MONO (-3221 3275);
FORCEPROP 2 LAST CDS_LIB standard
J 0
(-3000 3275);
PAINT MONO (-3000 3275);
DISPLAY INVISIBLE (-3000 3275);
FORCEPROP 1 LAST OFFPAGE TRUE
J 0
(-2675 3150);
DISPLAY 0.872340 (-2675 3150);
DISPLAY INVISIBLE (-2675 3150);
FORCEPROP 1 LAST COMMENT_BODY TRUE
J 0
(-2875 3175);
DISPLAY 0.872340 (-2875 3175);
PAINT GREEN (-2875 3175);
DISPLAY INVISIBLE (-2875 3175);
FORCEPROP 2 LAST PATH I16
J 0
(-2950 3350);
DISPLAY 1.021277 (-2950 3350);
DISPLAY INVISIBLE (-2950 3350);
FORCEADD TAP..1
(2500 3675);
FORCEPROP 3 LASTPIN (2450 3675) SIG_NAME M_F_CPU0_SA_DQS_DN<2>
J 0
(2460 3685);
DISPLAY 0.659574 (2460 3685);
PAINT MONO (2460 3685);
DISPLAY INVISIBLE (2460 3685);
FORCEPROP 1 LASTPIN (2450 3675) BN 2
J 0
(2438 3683);
DISPLAY 0.680851 (2438 3683);
PAINT GREEN (2438 3683);
FORCEPROP 2 LAST CDS_LIB standard
J 0
(2500 3675);
DISPLAY INVISIBLE (2500 3675);
FORCEPROP 1 LAST BODY_TYPE PLUMBING
J 0
(2500 3725);
DISPLAY 0.872340 (2500 3725);
PAINT GREEN (2500 3725);
DISPLAY INVISIBLE (2500 3725);
FORCEPROP 1 LAST HDL_TAP TRUE
J 0
(2825 3550);
DISPLAY 0.872340 (2825 3550);
DISPLAY INVISIBLE (2825 3550);
FORCEPROP 1 LAST PATH I160
J 0
(2498 3675);
DISPLAY 0.872340 (2498 3675);
PAINT GREEN (2498 3675);
DISPLAY INVISIBLE (2498 3675);
FORCEADD TAP..1
(2500 3875);
FORCEPROP 3 LASTPIN (2450 3875) SIG_NAME M_F_CPU0_SA_DQS_DN<4>
J 0
(2460 3885);
DISPLAY 0.659574 (2460 3885);
PAINT MONO (2460 3885);
DISPLAY INVISIBLE (2460 3885);
FORCEPROP 1 LASTPIN (2450 3875) BN 4
J 0
(2438 3883);
DISPLAY 0.680851 (2438 3883);
PAINT GREEN (2438 3883);
FORCEPROP 2 LAST CDS_LIB standard
J 0
(2500 3875);
PAINT MONO (2500 3875);
DISPLAY INVISIBLE (2500 3875);
FORCEPROP 1 LAST BODY_TYPE PLUMBING
J 0
(2500 3925);
DISPLAY 0.872340 (2500 3925);
PAINT GREEN (2500 3925);
DISPLAY INVISIBLE (2500 3925);
FORCEPROP 1 LAST HDL_TAP TRUE
J 0
(2825 3750);
DISPLAY 0.872340 (2825 3750);
DISPLAY INVISIBLE (2825 3750);
FORCEPROP 1 LAST PATH I161
J 0
(2498 3875);
DISPLAY 0.872340 (2498 3875);
PAINT GREEN (2498 3875);
DISPLAY INVISIBLE (2498 3875);
FORCEADD TAP..1
(2500 3775);
FORCEPROP 3 LASTPIN (2450 3775) SIG_NAME M_F_CPU0_SA_DQS_DN<3>
J 0
(2460 3785);
DISPLAY 0.659574 (2460 3785);
PAINT MONO (2460 3785);
DISPLAY INVISIBLE (2460 3785);
FORCEPROP 1 LASTPIN (2450 3775) BN 3
J 0
(2438 3783);
DISPLAY 0.680851 (2438 3783);
PAINT GREEN (2438 3783);
FORCEPROP 2 LAST CDS_LIB standard
J 0
(2500 3775);
PAINT MONO (2500 3775);
DISPLAY INVISIBLE (2500 3775);
FORCEPROP 1 LAST BODY_TYPE PLUMBING
J 0
(2500 3825);
DISPLAY 0.872340 (2500 3825);
PAINT GREEN (2500 3825);
DISPLAY INVISIBLE (2500 3825);
FORCEPROP 1 LAST HDL_TAP TRUE
J 0
(2825 3650);
DISPLAY 0.872340 (2825 3650);
DISPLAY INVISIBLE (2825 3650);
FORCEPROP 1 LAST PATH I162
J 0
(2498 3775);
DISPLAY 0.872340 (2498 3775);
PAINT GREEN (2498 3775);
DISPLAY INVISIBLE (2498 3775);
FORCEADD TAP..1
(2500 3975);
FORCEPROP 3 LASTPIN (2450 3975) SIG_NAME M_F_CPU0_SA_DQS_DN<5>
J 0
(2460 3985);
DISPLAY 0.659574 (2460 3985);
PAINT MONO (2460 3985);
DISPLAY INVISIBLE (2460 3985);
FORCEPROP 1 LASTPIN (2450 3975) BN 5
J 0
(2438 3983);
DISPLAY 0.680851 (2438 3983);
PAINT GREEN (2438 3983);
FORCEPROP 2 LAST CDS_LIB standard
J 0
(2500 3975);
DISPLAY INVISIBLE (2500 3975);
FORCEPROP 1 LAST BODY_TYPE PLUMBING
J 0
(2500 4025);
DISPLAY 0.872340 (2500 4025);
PAINT GREEN (2500 4025);
DISPLAY INVISIBLE (2500 4025);
FORCEPROP 1 LAST HDL_TAP TRUE
J 0
(2825 3850);
DISPLAY 0.872340 (2825 3850);
DISPLAY INVISIBLE (2825 3850);
FORCEPROP 1 LAST PATH I163
J 0
(2498 3975);
DISPLAY 0.872340 (2498 3975);
PAINT GREEN (2498 3975);
DISPLAY INVISIBLE (2498 3975);
FORCEADD TAP..1
(2500 4075);
FORCEPROP 3 LASTPIN (2450 4075) SIG_NAME M_F_CPU0_SA_DQS_DN<6>
J 0
(2460 4085);
DISPLAY 0.659574 (2460 4085);
PAINT MONO (2460 4085);
DISPLAY INVISIBLE (2460 4085);
FORCEPROP 1 LASTPIN (2450 4075) BN 6
J 0
(2438 4083);
DISPLAY 0.680851 (2438 4083);
PAINT GREEN (2438 4083);
FORCEPROP 2 LAST CDS_LIB standard
J 0
(2500 4075);
DISPLAY INVISIBLE (2500 4075);
FORCEPROP 1 LAST BODY_TYPE PLUMBING
J 0
(2500 4125);
DISPLAY 0.872340 (2500 4125);
PAINT GREEN (2500 4125);
DISPLAY INVISIBLE (2500 4125);
FORCEPROP 1 LAST HDL_TAP TRUE
J 0
(2825 3950);
DISPLAY 0.872340 (2825 3950);
DISPLAY INVISIBLE (2825 3950);
FORCEPROP 1 LAST PATH I164
J 0
(2498 4075);
DISPLAY 0.872340 (2498 4075);
PAINT GREEN (2498 4075);
DISPLAY INVISIBLE (2498 4075);
FORCEADD TAP..1
(2500 4175);
FORCEPROP 3 LASTPIN (2450 4175) SIG_NAME M_F_CPU0_SA_DQS_DN<7>
J 0
(2460 4185);
DISPLAY 0.659574 (2460 4185);
PAINT MONO (2460 4185);
DISPLAY INVISIBLE (2460 4185);
FORCEPROP 1 LASTPIN (2450 4175) BN 7
J 0
(2438 4183);
DISPLAY 0.680851 (2438 4183);
PAINT GREEN (2438 4183);
FORCEPROP 2 LAST CDS_LIB standard
J 0
(2500 4175);
DISPLAY INVISIBLE (2500 4175);
FORCEPROP 1 LAST BODY_TYPE PLUMBING
J 0
(2500 4225);
DISPLAY 0.872340 (2500 4225);
PAINT GREEN (2500 4225);
DISPLAY INVISIBLE (2500 4225);
FORCEPROP 1 LAST HDL_TAP TRUE
J 0
(2825 4050);
DISPLAY 0.872340 (2825 4050);
DISPLAY INVISIBLE (2825 4050);
FORCEPROP 1 LAST PATH I165
J 0
(2498 4175);
DISPLAY 0.872340 (2498 4175);
PAINT GREEN (2498 4175);
DISPLAY INVISIBLE (2498 4175);
FORCEADD TAP..1
(2500 4275);
FORCEPROP 3 LASTPIN (2450 4275) SIG_NAME M_F_CPU0_SA_DQS_DN<8>
J 0
(2460 4285);
DISPLAY 0.659574 (2460 4285);
PAINT MONO (2460 4285);
DISPLAY INVISIBLE (2460 4285);
FORCEPROP 1 LASTPIN (2450 4275) BN 8
J 0
(2438 4283);
DISPLAY 0.680851 (2438 4283);
PAINT GREEN (2438 4283);
FORCEPROP 2 LAST CDS_LIB standard
J 0
(2500 4275);
DISPLAY INVISIBLE (2500 4275);
FORCEPROP 1 LAST BODY_TYPE PLUMBING
J 0
(2500 4325);
DISPLAY 0.872340 (2500 4325);
PAINT GREEN (2500 4325);
DISPLAY INVISIBLE (2500 4325);
FORCEPROP 1 LAST HDL_TAP TRUE
J 0
(2825 4150);
DISPLAY 0.872340 (2825 4150);
DISPLAY INVISIBLE (2825 4150);
FORCEPROP 1 LAST PATH I166
J 0
(2498 4275);
DISPLAY 0.872340 (2498 4275);
PAINT GREEN (2498 4275);
DISPLAY INVISIBLE (2498 4275);
FORCEADD TAP..1
(2500 4375);
FORCEPROP 3 LASTPIN (2450 4375) SIG_NAME M_F_CPU0_SA_DQS_DN<9>
J 0
(2460 4385);
DISPLAY 0.659574 (2460 4385);
PAINT MONO (2460 4385);
DISPLAY INVISIBLE (2460 4385);
FORCEPROP 1 LASTPIN (2450 4375) BN 9
J 0
(2438 4383);
DISPLAY 0.680851 (2438 4383);
PAINT GREEN (2438 4383);
FORCEPROP 2 LAST CDS_LIB standard
J 0
(2500 4375);
DISPLAY INVISIBLE (2500 4375);
FORCEPROP 1 LAST BODY_TYPE PLUMBING
J 0
(2500 4425);
DISPLAY 0.872340 (2500 4425);
PAINT GREEN (2500 4425);
DISPLAY INVISIBLE (2500 4425);
FORCEPROP 1 LAST HDL_TAP TRUE
J 0
(2825 4250);
DISPLAY 0.872340 (2825 4250);
DISPLAY INVISIBLE (2825 4250);
FORCEPROP 1 LAST PATH I167
J 0
(2498 4375);
DISPLAY 0.872340 (2498 4375);
PAINT GREEN (2498 4375);
DISPLAY INVISIBLE (2498 4375);
FORCEADD OFFPAGE..2
(3450 3350);
FORCEPROP 2 LAST $XR1 92 
J 0
(3729 3350);
DISPLAY 0.638298 (3729 3350);
PAINT MONO (3729 3350);
FORCEPROP 2 LAST $XR0 25 
J 0
(3639 3350);
DISPLAY 0.638298 (3639 3350);
PAINT MONO (3639 3350);
FORCEPROP 2 LAST CDS_LIB standard
J 0
(3450 3350);
PAINT MONO (3450 3350);
DISPLAY INVISIBLE (3450 3350);
FORCEPROP 1 LAST OFFPAGE TRUE
J 0
(3775 3225);
DISPLAY 1.170213 (3775 3225);
PAINT GREEN (3775 3225);
DISPLAY INVISIBLE (3775 3225);
FORCEPROP 1 LAST COMMENT_BODY TRUE
J 0
(3405 3255);
DISPLAY 1.170213 (3405 3255);
PAINT GREEN (3405 3255);
DISPLAY INVISIBLE (3405 3255);
FORCEPROP 2 LAST PATH I168
J 0
(3625 3425);
DISPLAY 1.021277 (3625 3425);
DISPLAY INVISIBLE (3625 3425);
FORCEADD OFFPAGE..2
(3450 3400);
FORCEPROP 2 LAST $XR1 92 
J 0
(3729 3400);
DISPLAY 0.638298 (3729 3400);
PAINT MONO (3729 3400);
FORCEPROP 2 LAST $XR0 25 
J 0
(3639 3400);
DISPLAY 0.638298 (3639 3400);
PAINT MONO (3639 3400);
FORCEPROP 2 LAST CDS_LIB standard
J 0
(3450 3400);
PAINT MONO (3450 3400);
DISPLAY INVISIBLE (3450 3400);
FORCEPROP 1 LAST OFFPAGE TRUE
J 0
(3775 3275);
DISPLAY 1.170213 (3775 3275);
PAINT GREEN (3775 3275);
DISPLAY INVISIBLE (3775 3275);
FORCEPROP 1 LAST COMMENT_BODY TRUE
J 0
(3405 3305);
DISPLAY 1.170213 (3405 3305);
PAINT GREEN (3405 3305);
DISPLAY INVISIBLE (3405 3305);
FORCEPROP 2 LAST PATH I169
J 0
(3625 3475);
DISPLAY 1.021277 (3625 3475);
DISPLAY INVISIBLE (3625 3475);
FORCEADD OFFPAGE..1
(-3000 3325);
FORCEPROP 2 LAST $XR0 25 
J 0
(-3221 3325);
DISPLAY 0.638298 (-3221 3325);
PAINT MONO (-3221 3325);
FORCEPROP 2 LAST CDS_LIB standard
J 0
(-3000 3325);
PAINT MONO (-3000 3325);
DISPLAY INVISIBLE (-3000 3325);
FORCEPROP 1 LAST OFFPAGE TRUE
J 0
(-2675 3200);
DISPLAY 0.872340 (-2675 3200);
DISPLAY INVISIBLE (-2675 3200);
FORCEPROP 1 LAST COMMENT_BODY TRUE
J 0
(-2875 3225);
DISPLAY 0.872340 (-2875 3225);
PAINT GREEN (-2875 3225);
DISPLAY INVISIBLE (-2875 3225);
FORCEPROP 2 LAST PATH I17
J 0
(-2950 3400);
DISPLAY 1.021277 (-2950 3400);
DISPLAY INVISIBLE (-2950 3400);
FORCEADD OFFPAGE..2
(3450 4400);
FORCEPROP 2 LAST $XR1 92 
J 0
(3729 4400);
DISPLAY 0.638298 (3729 4400);
PAINT MONO (3729 4400);
FORCEPROP 2 LAST $XR0 25 
J 0
(3639 4400);
DISPLAY 0.638298 (3639 4400);
PAINT MONO (3639 4400);
FORCEPROP 2 LAST CDS_LIB standard
J 0
(3450 4400);
PAINT MONO (3450 4400);
DISPLAY INVISIBLE (3450 4400);
FORCEPROP 1 LAST OFFPAGE TRUE
J 0
(3775 4275);
DISPLAY 1.170213 (3775 4275);
PAINT GREEN (3775 4275);
DISPLAY INVISIBLE (3775 4275);
FORCEPROP 1 LAST COMMENT_BODY TRUE
J 0
(3405 4305);
DISPLAY 1.170213 (3405 4305);
PAINT GREEN (3405 4305);
DISPLAY INVISIBLE (3405 4305);
FORCEPROP 2 LAST PATH I170
J 0
(3625 4475);
DISPLAY 1.021277 (3625 4475);
DISPLAY INVISIBLE (3625 4475);
FORCEADD OFFPAGE..3
(400 4450);
FORCEPROP 2 LAST $XR1 92 
J 0
(704 4450);
DISPLAY 0.638298 (704 4450);
PAINT MONO (704 4450);
FORCEPROP 2 LAST $XR0 25 
J 0
(614 4450);
DISPLAY 0.638298 (614 4450);
PAINT MONO (614 4450);
FORCEPROP 2 LAST CDS_LIB standard
J 2
(400 4450);
DISPLAY INVISIBLE (400 4450);
FORCEPROP 1 LAST OFFPAGE TRUE
J 0
(725 4325);
DISPLAY 0.872340 (725 4325);
DISPLAY INVISIBLE (725 4325);
FORCEPROP 1 LAST COMMENT_BODY TRUE
J 0
(350 4350);
DISPLAY 0.872340 (350 4350);
PAINT GREEN (350 4350);
DISPLAY INVISIBLE (350 4350);
FORCEPROP 2 LAST PATH I171
J 0
(600 4525);
DISPLAY 1.021277 (600 4525);
DISPLAY INVISIBLE (600 4525);
FORCEADD TAP..1
(2325 4425);
FORCEPROP 3 LASTPIN (2275 4425) SIG_NAME M_F_CPU0_SA_DQS_DP<9>
J 0
(2285 4435);
DISPLAY 0.659574 (2285 4435);
PAINT MONO (2285 4435);
DISPLAY INVISIBLE (2285 4435);
FORCEPROP 1 LASTPIN (2275 4425) BN 9
J 0
(2263 4433);
DISPLAY 0.680851 (2263 4433);
PAINT GREEN (2263 4433);
FORCEPROP 2 LAST CDS_LIB standard
J 0
(2325 4425);
DISPLAY INVISIBLE (2325 4425);
FORCEPROP 1 LAST BODY_TYPE PLUMBING
J 0
(2325 4475);
DISPLAY 0.872340 (2325 4475);
PAINT GREEN (2325 4475);
DISPLAY INVISIBLE (2325 4475);
FORCEPROP 1 LAST HDL_TAP TRUE
J 0
(2650 4300);
DISPLAY 0.872340 (2650 4300);
DISPLAY INVISIBLE (2650 4300);
FORCEPROP 1 LAST PATH I172
J 0
(2323 4425);
DISPLAY 0.872340 (2323 4425);
PAINT GREEN (2323 4425);
DISPLAY INVISIBLE (2323 4425);
FORCEADD OFFPAGE..2
(3450 4450);
FORCEPROP 2 LAST $XR1 92 
J 0
(3729 4450);
DISPLAY 0.638298 (3729 4450);
PAINT MONO (3729 4450);
FORCEPROP 2 LAST $XR0 25 
J 0
(3639 4450);
DISPLAY 0.638298 (3639 4450);
PAINT MONO (3639 4450);
FORCEPROP 2 LAST CDS_LIB standard
J 0
(3450 4450);
PAINT MONO (3450 4450);
DISPLAY INVISIBLE (3450 4450);
FORCEPROP 1 LAST OFFPAGE TRUE
J 0
(3775 4325);
DISPLAY 1.170213 (3775 4325);
PAINT GREEN (3775 4325);
DISPLAY INVISIBLE (3775 4325);
FORCEPROP 1 LAST COMMENT_BODY TRUE
J 0
(3405 4355);
DISPLAY 1.170213 (3405 4355);
PAINT GREEN (3405 4355);
DISPLAY INVISIBLE (3405 4355);
FORCEPROP 2 LAST PATH I173
J 0
(3625 4525);
DISPLAY 1.021277 (3625 4525);
DISPLAY INVISIBLE (3625 4525);
FORCEADD UNIVERSAL_GND..1
(4000 725);
FORCEPROP 3 LASTPIN (4000 775) SIG_NAME GND\g
J 0
(4010 785);
DISPLAY 0.659574 (4010 785);
PAINT MONO (4010 785);
DISPLAY INVISIBLE (4010 785);
FORCEPROP 2 LAST CDS_LIB logical_power
J 0
(4000 725);
PAINT MONO (4000 725);
DISPLAY INVISIBLE (4000 725);
FORCEPROP 1 LAST HDL_POWER GND
J 1
(4025 650);
DISPLAY 0.872340 (4025 650);
PAINT GREEN (4025 650);
DISPLAY INVISIBLE (4025 650);
FORCEPROP 1 LAST PATH I174
J 0
(4075 725);
DISPLAY 0.872340 (4075 725);
PAINT AQUA (4075 725);
DISPLAY INVISIBLE (4075 725);
FORCEADD SCONN288_ADR50017P087CC..3
(4850 2800);
FORCEPROP 1 LAST PART_NUMBER DFHST8FS460
J 0
(4395 4724);
DISPLAY 0.723404 (4395 4724);
PAINT GREEN (4395 4724);
DISPLAY INVISIBLE (4395 4724);
FORCEPROP 1 LAST MATERIAL IO
J 0
(4395 4597);
DISPLAY 0.723404 (4395 4597);
PAINT GREEN (4395 4597);
FORCEPROP 2 LAST PART_TYPE SMLF
J 0
(4400 4875);
DISPLAY 1.021277 (4400 4875);
FORCEPROP 2 LAST VALUE SCONN288_ADR50017-P087CC
J 0
(4400 4825);
DISPLAY 1.021277 (4400 4825);
FORCEPROP 1 LAST $LOCATION J12
J 0
(4400 4775);
DISPLAY 0.723404 (4400 4775);
PAINT GREEN (4400 4775);
FORCEPROP 0 LASTPIN (5450 1175) $PN G1
J 0
(5460 1185);
DISPLAY 0.680851 (5460 1185);
PAINT MONO (5460 1185);
FORCEPROP 0 LASTPIN (5450 1125) $PN G2
J 0
(5460 1135);
DISPLAY 0.680851 (5460 1135);
PAINT MONO (5460 1135);
FORCEPROP 0 LASTPIN (5450 1075) $PN G3
J 0
(5460 1085);
DISPLAY 0.680851 (5460 1085);
PAINT MONO (5460 1085);
FORCEPROP 0 LASTPIN (4250 4325) $PN 1
J 2
(4240 4335);
DISPLAY 0.680851 (4240 4335);
PAINT MONO (4240 4335);
FORCEPROP 0 LASTPIN (4250 4375) $PN 145
J 2
(4240 4385);
DISPLAY 0.680851 (4240 4385);
PAINT MONO (4240 4385);
FORCEPROP 0 LASTPIN (4250 4425) $PN 146
J 2
(4240 4435);
DISPLAY 0.680851 (4240 4435);
PAINT MONO (4240 4435);
FORCEPROP 0 LASTPIN (5450 1275) $PN 6
J 0
(5460 1285);
DISPLAY 0.680851 (5460 1285);
PAINT MONO (5460 1285);
FORCEPROP 0 LASTPIN (5450 1325) $PN 8
J 0
(5460 1335);
DISPLAY 0.680851 (5460 1335);
PAINT MONO (5460 1335);
FORCEPROP 0 LASTPIN (5450 1375) $PN 10
J 0
(5460 1385);
DISPLAY 0.680851 (5460 1385);
PAINT MONO (5460 1385);
FORCEPROP 0 LASTPIN (5450 1425) $PN 13
J 0
(5460 1435);
DISPLAY 0.680851 (5460 1435);
PAINT MONO (5460 1435);
FORCEPROP 0 LASTPIN (5450 1475) $PN 15
J 0
(5460 1485);
DISPLAY 0.680851 (5460 1485);
PAINT MONO (5460 1485);
FORCEPROP 0 LASTPIN (5450 1525) $PN 17
J 0
(5460 1535);
DISPLAY 0.680851 (5460 1535);
PAINT MONO (5460 1535);
FORCEPROP 0 LASTPIN (5450 1575) $PN 19
J 0
(5460 1585);
DISPLAY 0.680851 (5460 1585);
PAINT MONO (5460 1585);
FORCEPROP 0 LASTPIN (5450 1625) $PN 21
J 0
(5460 1635);
DISPLAY 0.680851 (5460 1635);
PAINT MONO (5460 1635);
FORCEPROP 0 LASTPIN (5450 1675) $PN 24
J 0
(5460 1685);
DISPLAY 0.680851 (5460 1685);
PAINT MONO (5460 1685);
FORCEPROP 0 LASTPIN (5450 1725) $PN 26
J 0
(5460 1735);
DISPLAY 0.680851 (5460 1735);
PAINT MONO (5460 1735);
FORCEPROP 0 LASTPIN (5450 1775) $PN 28
J 0
(5460 1785);
DISPLAY 0.680851 (5460 1785);
PAINT MONO (5460 1785);
FORCEPROP 0 LASTPIN (5450 1825) $PN 30
J 0
(5460 1835);
DISPLAY 0.680851 (5460 1835);
PAINT MONO (5460 1835);
FORCEPROP 0 LASTPIN (5450 1875) $PN 32
J 0
(5460 1885);
DISPLAY 0.680851 (5460 1885);
PAINT MONO (5460 1885);
FORCEPROP 0 LASTPIN (5450 1925) $PN 35
J 0
(5460 1935);
DISPLAY 0.680851 (5460 1935);
PAINT MONO (5460 1935);
FORCEPROP 0 LASTPIN (5450 1975) $PN 37
J 0
(5460 1985);
DISPLAY 0.680851 (5460 1985);
PAINT MONO (5460 1985);
FORCEPROP 0 LASTPIN (5450 2025) $PN 39
J 0
(5460 2035);
DISPLAY 0.680851 (5460 2035);
PAINT MONO (5460 2035);
FORCEPROP 0 LASTPIN (5450 2075) $PN 41
J 0
(5460 2085);
DISPLAY 0.680851 (5460 2085);
PAINT MONO (5460 2085);
FORCEPROP 0 LASTPIN (5450 2125) $PN 43
J 0
(5460 2135);
DISPLAY 0.680851 (5460 2135);
PAINT MONO (5460 2135);
FORCEPROP 0 LASTPIN (5450 2175) $PN 46
J 0
(5460 2185);
DISPLAY 0.680851 (5460 2185);
PAINT MONO (5460 2185);
FORCEPROP 0 LASTPIN (5450 2225) $PN 48
J 0
(5460 2235);
DISPLAY 0.680851 (5460 2235);
PAINT MONO (5460 2235);
FORCEPROP 0 LASTPIN (5450 2275) $PN 50
J 0
(5460 2285);
DISPLAY 0.680851 (5460 2285);
PAINT MONO (5460 2285);
FORCEPROP 0 LASTPIN (5450 2325) $PN 52
J 0
(5460 2335);
DISPLAY 0.680851 (5460 2335);
PAINT MONO (5460 2335);
FORCEPROP 0 LASTPIN (5450 2375) $PN 54
J 0
(5460 2385);
DISPLAY 0.680851 (5460 2385);
PAINT MONO (5460 2385);
FORCEPROP 0 LASTPIN (5450 2425) $PN 57
J 0
(5460 2435);
DISPLAY 0.680851 (5460 2435);
PAINT MONO (5460 2435);
FORCEPROP 0 LASTPIN (5450 2475) $PN 59
J 0
(5460 2485);
DISPLAY 0.680851 (5460 2485);
PAINT MONO (5460 2485);
FORCEPROP 0 LASTPIN (5450 2525) $PN 61
J 0
(5460 2535);
DISPLAY 0.680851 (5460 2535);
PAINT MONO (5460 2535);
FORCEPROP 0 LASTPIN (5450 2575) $PN 63
J 0
(5460 2585);
DISPLAY 0.680851 (5460 2585);
PAINT MONO (5460 2585);
FORCEPROP 0 LASTPIN (5450 2625) $PN 65
J 0
(5460 2635);
DISPLAY 0.680851 (5460 2635);
PAINT MONO (5460 2635);
FORCEPROP 0 LASTPIN (5450 2675) $PN 67
J 0
(5460 2685);
DISPLAY 0.680851 (5460 2685);
PAINT MONO (5460 2685);
FORCEPROP 0 LASTPIN (5450 2725) $PN 69
J 0
(5460 2735);
DISPLAY 0.680851 (5460 2735);
PAINT MONO (5460 2735);
FORCEPROP 0 LASTPIN (5450 2775) $PN 71
J 0
(5460 2785);
DISPLAY 0.680851 (5460 2785);
PAINT MONO (5460 2785);
FORCEPROP 0 LASTPIN (5450 2825) $PN 73
J 0
(5460 2835);
DISPLAY 0.680851 (5460 2835);
PAINT MONO (5460 2835);
FORCEPROP 0 LASTPIN (5450 2875) $PN 75
J 0
(5460 2885);
DISPLAY 0.680851 (5460 2885);
PAINT MONO (5460 2885);
FORCEPROP 0 LASTPIN (5450 2925) $PN 77
J 0
(5460 2935);
DISPLAY 0.680851 (5460 2935);
PAINT MONO (5460 2935);
FORCEPROP 0 LASTPIN (5450 2975) $PN 79
J 0
(5460 2985);
DISPLAY 0.680851 (5460 2985);
PAINT MONO (5460 2985);
FORCEPROP 0 LASTPIN (5450 3025) $PN 81
J 0
(5460 3035);
DISPLAY 0.680851 (5460 3035);
PAINT MONO (5460 3035);
FORCEPROP 0 LASTPIN (5450 3075) $PN 83
J 0
(5460 3085);
DISPLAY 0.680851 (5460 3085);
PAINT MONO (5460 3085);
FORCEPROP 0 LASTPIN (5450 3125) $PN 85
J 0
(5460 3135);
DISPLAY 0.680851 (5460 3135);
PAINT MONO (5460 3135);
FORCEPROP 0 LASTPIN (5450 3175) $PN 88
J 0
(5460 3185);
DISPLAY 0.680851 (5460 3185);
PAINT MONO (5460 3185);
FORCEPROP 0 LASTPIN (5450 3225) $PN 90
J 0
(5460 3235);
DISPLAY 0.680851 (5460 3235);
PAINT MONO (5460 3235);
FORCEPROP 0 LASTPIN (5450 3275) $PN 92
J 0
(5460 3285);
DISPLAY 0.680851 (5460 3285);
PAINT MONO (5460 3285);
FORCEPROP 0 LASTPIN (5450 3325) $PN 95
J 0
(5460 3335);
DISPLAY 0.680851 (5460 3335);
PAINT MONO (5460 3335);
FORCEPROP 0 LASTPIN (5450 3375) $PN 97
J 0
(5460 3385);
DISPLAY 0.680851 (5460 3385);
PAINT MONO (5460 3385);
FORCEPROP 0 LASTPIN (5450 3425) $PN 99
J 0
(5460 3435);
DISPLAY 0.680851 (5460 3435);
PAINT MONO (5460 3435);
FORCEPROP 0 LASTPIN (5450 3475) $PN 101
J 0
(5460 3485);
DISPLAY 0.680851 (5460 3485);
PAINT MONO (5460 3485);
FORCEPROP 0 LASTPIN (5450 3525) $PN 103
J 0
(5460 3535);
DISPLAY 0.680851 (5460 3535);
PAINT MONO (5460 3535);
FORCEPROP 0 LASTPIN (5450 3575) $PN 106
J 0
(5460 3585);
DISPLAY 0.680851 (5460 3585);
PAINT MONO (5460 3585);
FORCEPROP 0 LASTPIN (5450 3625) $PN 108
J 0
(5460 3635);
DISPLAY 0.680851 (5460 3635);
PAINT MONO (5460 3635);
FORCEPROP 0 LASTPIN (5450 3675) $PN 110
J 0
(5460 3685);
DISPLAY 0.680851 (5460 3685);
PAINT MONO (5460 3685);
FORCEPROP 0 LASTPIN (5450 3725) $PN 112
J 0
(5460 3735);
DISPLAY 0.680851 (5460 3735);
PAINT MONO (5460 3735);
FORCEPROP 0 LASTPIN (5450 3775) $PN 114
J 0
(5460 3785);
DISPLAY 0.680851 (5460 3785);
PAINT MONO (5460 3785);
FORCEPROP 0 LASTPIN (5450 3825) $PN 117
J 0
(5460 3835);
DISPLAY 0.680851 (5460 3835);
PAINT MONO (5460 3835);
FORCEPROP 0 LASTPIN (5450 3875) $PN 119
J 0
(5460 3885);
DISPLAY 0.680851 (5460 3885);
PAINT MONO (5460 3885);
FORCEPROP 0 LASTPIN (5450 3925) $PN 121
J 0
(5460 3935);
DISPLAY 0.680851 (5460 3935);
PAINT MONO (5460 3935);
FORCEPROP 0 LASTPIN (5450 3975) $PN 123
J 0
(5460 3985);
DISPLAY 0.680851 (5460 3985);
PAINT MONO (5460 3985);
FORCEPROP 0 LASTPIN (5450 4025) $PN 125
J 0
(5460 4035);
DISPLAY 0.680851 (5460 4035);
PAINT MONO (5460 4035);
FORCEPROP 0 LASTPIN (5450 4075) $PN 128
J 0
(5460 4085);
DISPLAY 0.680851 (5460 4085);
PAINT MONO (5460 4085);
FORCEPROP 0 LASTPIN (5450 4125) $PN 130
J 0
(5460 4135);
DISPLAY 0.680851 (5460 4135);
PAINT MONO (5460 4135);
FORCEPROP 0 LASTPIN (5450 4175) $PN 132
J 0
(5460 4185);
DISPLAY 0.680851 (5460 4185);
PAINT MONO (5460 4185);
FORCEPROP 0 LASTPIN (5450 4225) $PN 134
J 0
(5460 4235);
DISPLAY 0.680851 (5460 4235);
PAINT MONO (5460 4235);
FORCEPROP 0 LASTPIN (5450 4275) $PN 136
J 0
(5460 4285);
DISPLAY 0.680851 (5460 4285);
PAINT MONO (5460 4285);
FORCEPROP 0 LASTPIN (5450 4325) $PN 139
J 0
(5460 4335);
DISPLAY 0.680851 (5460 4335);
PAINT MONO (5460 4335);
FORCEPROP 0 LASTPIN (5450 4375) $PN 141
J 0
(5460 4385);
DISPLAY 0.680851 (5460 4385);
PAINT MONO (5460 4385);
FORCEPROP 0 LASTPIN (5450 4425) $PN 143
J 0
(5460 4435);
DISPLAY 0.680851 (5460 4435);
PAINT MONO (5460 4435);
FORCEPROP 0 LASTPIN (4250 1175) $PN 151
J 2
(4240 1185);
DISPLAY 0.680851 (4240 1185);
PAINT MONO (4240 1185);
FORCEPROP 0 LASTPIN (4250 1225) $PN 153
J 2
(4240 1235);
DISPLAY 0.680851 (4240 1235);
PAINT MONO (4240 1235);
FORCEPROP 0 LASTPIN (4250 1275) $PN 155
J 2
(4240 1285);
DISPLAY 0.680851 (4240 1285);
PAINT MONO (4240 1285);
FORCEPROP 0 LASTPIN (4250 1325) $PN 158
J 2
(4240 1335);
DISPLAY 0.680851 (4240 1335);
PAINT MONO (4240 1335);
FORCEPROP 0 LASTPIN (4250 1375) $PN 160
J 2
(4240 1385);
DISPLAY 0.680851 (4240 1385);
PAINT MONO (4240 1385);
FORCEPROP 0 LASTPIN (4250 1425) $PN 162
J 2
(4240 1435);
DISPLAY 0.680851 (4240 1435);
PAINT MONO (4240 1435);
FORCEPROP 0 LASTPIN (4250 1475) $PN 164
J 2
(4240 1485);
DISPLAY 0.680851 (4240 1485);
PAINT MONO (4240 1485);
FORCEPROP 0 LASTPIN (4250 1525) $PN 166
J 2
(4240 1535);
DISPLAY 0.680851 (4240 1535);
PAINT MONO (4240 1535);
FORCEPROP 0 LASTPIN (4250 1575) $PN 169
J 2
(4240 1585);
DISPLAY 0.680851 (4240 1585);
PAINT MONO (4240 1585);
FORCEPROP 0 LASTPIN (4250 1625) $PN 171
J 2
(4240 1635);
DISPLAY 0.680851 (4240 1635);
PAINT MONO (4240 1635);
FORCEPROP 0 LASTPIN (4250 1675) $PN 173
J 2
(4240 1685);
DISPLAY 0.680851 (4240 1685);
PAINT MONO (4240 1685);
FORCEPROP 0 LASTPIN (4250 1725) $PN 175
J 2
(4240 1735);
DISPLAY 0.680851 (4240 1735);
PAINT MONO (4240 1735);
FORCEPROP 0 LASTPIN (4250 1775) $PN 177
J 2
(4240 1785);
DISPLAY 0.680851 (4240 1785);
PAINT MONO (4240 1785);
FORCEPROP 0 LASTPIN (4250 1825) $PN 180
J 2
(4240 1835);
DISPLAY 0.680851 (4240 1835);
PAINT MONO (4240 1835);
FORCEPROP 0 LASTPIN (4250 1875) $PN 182
J 2
(4240 1885);
DISPLAY 0.680851 (4240 1885);
PAINT MONO (4240 1885);
FORCEPROP 0 LASTPIN (4250 1925) $PN 184
J 2
(4240 1935);
DISPLAY 0.680851 (4240 1935);
PAINT MONO (4240 1935);
FORCEPROP 0 LASTPIN (4250 1975) $PN 186
J 2
(4240 1985);
DISPLAY 0.680851 (4240 1985);
PAINT MONO (4240 1985);
FORCEPROP 0 LASTPIN (4250 2025) $PN 188
J 2
(4240 2035);
DISPLAY 0.680851 (4240 2035);
PAINT MONO (4240 2035);
FORCEPROP 0 LASTPIN (4250 2075) $PN 191
J 2
(4240 2085);
DISPLAY 0.680851 (4240 2085);
PAINT MONO (4240 2085);
FORCEPROP 0 LASTPIN (4250 2125) $PN 193
J 2
(4240 2135);
DISPLAY 0.680851 (4240 2135);
PAINT MONO (4240 2135);
FORCEPROP 0 LASTPIN (4250 2175) $PN 195
J 2
(4240 2185);
DISPLAY 0.680851 (4240 2185);
PAINT MONO (4240 2185);
FORCEPROP 0 LASTPIN (4250 2225) $PN 197
J 2
(4240 2235);
DISPLAY 0.680851 (4240 2235);
PAINT MONO (4240 2235);
FORCEPROP 0 LASTPIN (4250 2275) $PN 199
J 2
(4240 2285);
DISPLAY 0.680851 (4240 2285);
PAINT MONO (4240 2285);
FORCEPROP 0 LASTPIN (4250 2325) $PN 202
J 2
(4240 2335);
DISPLAY 0.680851 (4240 2335);
PAINT MONO (4240 2335);
FORCEPROP 0 LASTPIN (4250 2375) $PN 204
J 2
(4240 2385);
DISPLAY 0.680851 (4240 2385);
PAINT MONO (4240 2385);
FORCEPROP 0 LASTPIN (4250 2425) $PN 206
J 2
(4240 2435);
DISPLAY 0.680851 (4240 2435);
PAINT MONO (4240 2435);
FORCEPROP 0 LASTPIN (4250 2475) $PN 208
J 2
(4240 2485);
DISPLAY 0.680851 (4240 2485);
PAINT MONO (4240 2485);
FORCEPROP 0 LASTPIN (4250 2525) $PN 210
J 2
(4240 2535);
DISPLAY 0.680851 (4240 2535);
PAINT MONO (4240 2535);
FORCEPROP 0 LASTPIN (4250 2575) $PN 212
J 2
(4240 2585);
DISPLAY 0.680851 (4240 2585);
PAINT MONO (4240 2585);
FORCEPROP 0 LASTPIN (4250 2625) $PN 214
J 2
(4240 2635);
DISPLAY 0.680851 (4240 2635);
PAINT MONO (4240 2635);
FORCEPROP 0 LASTPIN (4250 2675) $PN 216
J 2
(4240 2685);
DISPLAY 0.680851 (4240 2685);
PAINT MONO (4240 2685);
FORCEPROP 0 LASTPIN (4250 2725) $PN 219
J 2
(4240 2735);
DISPLAY 0.680851 (4240 2735);
PAINT MONO (4240 2735);
FORCEPROP 0 LASTPIN (4250 2775) $PN 222
J 2
(4240 2785);
DISPLAY 0.680851 (4240 2785);
PAINT MONO (4240 2785);
FORCEPROP 0 LASTPIN (4250 2825) $PN 224
J 2
(4240 2835);
DISPLAY 0.680851 (4240 2835);
PAINT MONO (4240 2835);
FORCEPROP 0 LASTPIN (4250 2875) $PN 226
J 2
(4240 2885);
DISPLAY 0.680851 (4240 2885);
PAINT MONO (4240 2885);
FORCEPROP 0 LASTPIN (4250 2925) $PN 228
J 2
(4240 2935);
DISPLAY 0.680851 (4240 2935);
PAINT MONO (4240 2935);
FORCEPROP 0 LASTPIN (4250 2975) $PN 230
J 2
(4240 2985);
DISPLAY 0.680851 (4240 2985);
PAINT MONO (4240 2985);
FORCEPROP 0 LASTPIN (4250 3025) $PN 233
J 2
(4240 3035);
DISPLAY 0.680851 (4240 3035);
PAINT MONO (4240 3035);
FORCEPROP 0 LASTPIN (4250 3075) $PN 235
J 2
(4240 3085);
DISPLAY 0.680851 (4240 3085);
PAINT MONO (4240 3085);
FORCEPROP 0 LASTPIN (4250 3125) $PN 237
J 2
(4240 3135);
DISPLAY 0.680851 (4240 3135);
PAINT MONO (4240 3135);
FORCEPROP 0 LASTPIN (4250 3175) $PN 240
J 2
(4240 3185);
DISPLAY 0.680851 (4240 3185);
PAINT MONO (4240 3185);
FORCEPROP 0 LASTPIN (4250 3225) $PN 242
J 2
(4240 3235);
DISPLAY 0.680851 (4240 3235);
PAINT MONO (4240 3235);
FORCEPROP 0 LASTPIN (4250 3275) $PN 244
J 2
(4240 3285);
DISPLAY 0.680851 (4240 3285);
PAINT MONO (4240 3285);
FORCEPROP 0 LASTPIN (4250 3325) $PN 246
J 2
(4240 3335);
DISPLAY 0.680851 (4240 3335);
PAINT MONO (4240 3335);
FORCEPROP 0 LASTPIN (4250 3375) $PN 248
J 2
(4240 3385);
DISPLAY 0.680851 (4240 3385);
PAINT MONO (4240 3385);
FORCEPROP 0 LASTPIN (4250 3425) $PN 251
J 2
(4240 3435);
DISPLAY 0.680851 (4240 3435);
PAINT MONO (4240 3435);
FORCEPROP 0 LASTPIN (4250 3475) $PN 253
J 2
(4240 3485);
DISPLAY 0.680851 (4240 3485);
PAINT MONO (4240 3485);
FORCEPROP 0 LASTPIN (4250 3525) $PN 255
J 2
(4240 3535);
DISPLAY 0.680851 (4240 3535);
PAINT MONO (4240 3535);
FORCEPROP 0 LASTPIN (4250 3575) $PN 257
J 2
(4240 3585);
DISPLAY 0.680851 (4240 3585);
PAINT MONO (4240 3585);
FORCEPROP 0 LASTPIN (4250 3625) $PN 259
J 2
(4240 3635);
DISPLAY 0.680851 (4240 3635);
PAINT MONO (4240 3635);
FORCEPROP 0 LASTPIN (4250 3675) $PN 262
J 2
(4240 3685);
DISPLAY 0.680851 (4240 3685);
PAINT MONO (4240 3685);
FORCEPROP 0 LASTPIN (4250 3725) $PN 264
J 2
(4240 3735);
DISPLAY 0.680851 (4240 3735);
PAINT MONO (4240 3735);
FORCEPROP 0 LASTPIN (4250 3775) $PN 266
J 2
(4240 3785);
DISPLAY 0.680851 (4240 3785);
PAINT MONO (4240 3785);
FORCEPROP 0 LASTPIN (4250 3825) $PN 268
J 2
(4240 3835);
DISPLAY 0.680851 (4240 3835);
PAINT MONO (4240 3835);
FORCEPROP 0 LASTPIN (4250 3875) $PN 270
J 2
(4240 3885);
DISPLAY 0.680851 (4240 3885);
PAINT MONO (4240 3885);
FORCEPROP 0 LASTPIN (4250 3925) $PN 273
J 2
(4240 3935);
DISPLAY 0.680851 (4240 3935);
PAINT MONO (4240 3935);
FORCEPROP 0 LASTPIN (4250 3975) $PN 275
J 2
(4240 3985);
DISPLAY 0.680851 (4240 3985);
PAINT MONO (4240 3985);
FORCEPROP 0 LASTPIN (4250 4025) $PN 277
J 2
(4240 4035);
DISPLAY 0.680851 (4240 4035);
PAINT MONO (4240 4035);
FORCEPROP 0 LASTPIN (4250 4075) $PN 279
J 2
(4240 4085);
DISPLAY 0.680851 (4240 4085);
PAINT MONO (4240 4085);
FORCEPROP 0 LASTPIN (4250 4125) $PN 281
J 2
(4240 4135);
DISPLAY 0.680851 (4240 4135);
PAINT MONO (4240 4135);
FORCEPROP 0 LASTPIN (4250 4175) $PN 284
J 2
(4240 4185);
DISPLAY 0.680851 (4240 4185);
PAINT MONO (4240 4185);
FORCEPROP 0 LASTPIN (4250 4225) $PN 286
J 2
(4240 4235);
DISPLAY 0.680851 (4240 4235);
PAINT MONO (4240 4235);
FORCEPROP 0 LASTPIN (4250 4275) $PN 288
J 2
(4240 4285);
DISPLAY 0.680851 (4240 4285);
PAINT MONO (4240 4285);
FORCEPROP 1 LAST NEEDS_NO_SIZE TRUE
J 0
(4850 2800);
DISPLAY 0.723404 (4850 2800);
PAINT GREEN (4850 2800);
DISPLAY INVISIBLE (4850 2800);
FORCEPROP 1 LAST CDS_LMAN_SYM_OUTLINE -450,1775,450,-1775
J 0
(4850 2800);
DISPLAY 0.468085 (4850 2800);
PAINT GREEN (4850 2800);
DISPLAY INVISIBLE (4850 2800);
FORCEPROP 2 LAST CDS_LIB pure_quanta
J 0
(4850 2800);
DISPLAY INVISIBLE (4850 2800);
FORCEPROP 2 LAST CDS_LOCATION J12
J 0
(4400 4925);
DISPLAY 1.021277 (4400 4925);
DISPLAY INVISIBLE (4400 4925);
FORCEPROP 0 LAST $SEC 3
J 0
(4400 4925);
DISPLAY 0.680851 (4400 4925);
PAINT MONO (4400 4925);
DISPLAY INVISIBLE (4400 4925);
FORCEPROP 2 LAST CDS_SEC 3
J 0
(4400 4925);
DISPLAY 1.021277 (4400 4925);
DISPLAY INVISIBLE (4400 4925);
FORCEPROP 1 LAST PATH I175
J 0
(4850 2800);
DISPLAY 0.723404 (4850 2800);
PAINT GREEN (4850 2800);
DISPLAY INVISIBLE (4850 2800);
FORCEADD UNIVERSAL_GND..1
(5700 725);
FORCEPROP 3 LASTPIN (5700 775) SIG_NAME GND\g
J 0
(5710 785);
DISPLAY 0.659574 (5710 785);
PAINT MONO (5710 785);
DISPLAY INVISIBLE (5710 785);
FORCEPROP 2 LAST CDS_LIB logical_power
J 0
(5700 725);
PAINT MONO (5700 725);
DISPLAY INVISIBLE (5700 725);
FORCEPROP 1 LAST HDL_POWER GND
J 1
(5725 650);
DISPLAY 0.872340 (5725 650);
PAINT GREEN (5725 650);
DISPLAY INVISIBLE (5725 650);
FORCEPROP 1 LAST PATH I176
J 0
(5775 725);
DISPLAY 0.872340 (5775 725);
PAINT AQUA (5775 725);
DISPLAY INVISIBLE (5775 725);
FORCEADD VCC_CORE..1
(4000 4975);
FORCEPROP 3 LASTPIN (4000 4925) SIG_NAME P12V_S3_AUX_CPU0_NVDIMM\g
J 0
(4010 4935);
DISPLAY 0.659574 (4010 4935);
PAINT MONO (4010 4935);
DISPLAY INVISIBLE (4010 4935);
FORCEPROP 1 LAST HDL_POWER P12V_S3_AUX_CPU0_NVDIMM
J 1
(4000 5025);
DISPLAY 1.148936 (4000 5025);
PAINT GREEN (4000 5025);
FORCEPROP 2 LAST CDS_LIB logical_power
J 0
(4000 4975);
PAINT MONO (4000 4975);
DISPLAY INVISIBLE (4000 4975);
FORCEPROP 1 LAST PATH I177
J 0
(4050 5000);
DISPLAY 0.872340 (4050 5000);
PAINT AQUA (4050 5000);
DISPLAY INVISIBLE (4050 5000);
FORCEADD SCONN288_ADR50017P087CC..2
(1425 3425);
FORCEPROP 1 LAST PART_NUMBER DFHST8FS460
J 0
(820 4713);
DISPLAY 0.723404 (820 4713);
PAINT GREEN (820 4713);
DISPLAY INVISIBLE (820 4713);
FORCEPROP 2 LAST PART_TYPE SMLF
J 0
(825 4950);
DISPLAY 1.021277 (825 4950);
FORCEPROP 1 LAST MATERIAL IO
J 0
(820 4586);
DISPLAY 0.723404 (820 4586);
PAINT GREEN (820 4586);
FORCEPROP 2 LAST VALUE SCONN288_ADR50017-P087CC
J 0
(825 4900);
DISPLAY 1.021277 (825 4900);
FORCEPROP 1 LAST LOCATION J12
J 0
(820 4860);
DISPLAY 0.723404 (820 4860);
PAINT GREEN (820 4860);
FORCEPROP 0 LASTPIN (2175 3475) $PN 12
J 0
(2185 3485);
DISPLAY 0.680851 (2185 3485);
PAINT MONO (2185 3485);
FORCEPROP 0 LASTPIN (2175 3525) $PN 11
J 0
(2185 3535);
DISPLAY 0.680851 (2185 3535);
PAINT MONO (2185 3535);
FORCEPROP 0 LASTPIN (2175 2425) $PN 105
J 0
(2185 2435);
DISPLAY 0.680851 (2185 2435);
PAINT MONO (2185 2435);
FORCEPROP 0 LASTPIN (2175 2475) $PN 104
J 0
(2185 2485);
DISPLAY 0.680851 (2185 2485);
PAINT MONO (2185 2485);
FORCEPROP 0 LASTPIN (2175 3575) $PN 23
J 0
(2185 3585);
DISPLAY 0.680851 (2185 3585);
PAINT MONO (2185 3585);
FORCEPROP 0 LASTPIN (2175 3625) $PN 22
J 0
(2185 3635);
DISPLAY 0.680851 (2185 3635);
PAINT MONO (2185 3635);
FORCEPROP 0 LASTPIN (2175 2525) $PN 116
J 0
(2185 2535);
DISPLAY 0.680851 (2185 2535);
PAINT MONO (2185 2535);
FORCEPROP 0 LASTPIN (2175 2575) $PN 115
J 0
(2185 2585);
DISPLAY 0.680851 (2185 2585);
PAINT MONO (2185 2585);
FORCEPROP 0 LASTPIN (2175 3675) $PN 34
J 0
(2185 3685);
DISPLAY 0.680851 (2185 3685);
PAINT MONO (2185 3685);
FORCEPROP 0 LASTPIN (2175 3725) $PN 33
J 0
(2185 3735);
DISPLAY 0.680851 (2185 3735);
PAINT MONO (2185 3735);
FORCEPROP 0 LASTPIN (2175 2625) $PN 127
J 0
(2185 2635);
DISPLAY 0.680851 (2185 2635);
PAINT MONO (2185 2635);
FORCEPROP 0 LASTPIN (2175 2675) $PN 126
J 0
(2185 2685);
DISPLAY 0.680851 (2185 2685);
PAINT MONO (2185 2685);
FORCEPROP 0 LASTPIN (2175 3775) $PN 45
J 0
(2185 3785);
DISPLAY 0.680851 (2185 3785);
PAINT MONO (2185 3785);
FORCEPROP 0 LASTPIN (2175 3825) $PN 44
J 0
(2185 3835);
DISPLAY 0.680851 (2185 3835);
PAINT MONO (2185 3835);
FORCEPROP 0 LASTPIN (2175 2725) $PN 138
J 0
(2185 2735);
DISPLAY 0.680851 (2185 2735);
PAINT MONO (2185 2735);
FORCEPROP 0 LASTPIN (2175 2775) $PN 137
J 0
(2185 2785);
DISPLAY 0.680851 (2185 2785);
PAINT MONO (2185 2785);
FORCEPROP 0 LASTPIN (2175 3875) $PN 56
J 0
(2185 3885);
DISPLAY 0.680851 (2185 3885);
PAINT MONO (2185 3885);
FORCEPROP 0 LASTPIN (2175 3925) $PN 55
J 0
(2185 3935);
DISPLAY 0.680851 (2185 3935);
PAINT MONO (2185 3935);
FORCEPROP 0 LASTPIN (2175 2825) $PN 238
J 0
(2185 2835);
DISPLAY 0.680851 (2185 2835);
PAINT MONO (2185 2835);
FORCEPROP 0 LASTPIN (2175 2875) $PN 239
J 0
(2185 2885);
DISPLAY 0.680851 (2185 2885);
PAINT MONO (2185 2885);
FORCEPROP 0 LASTPIN (2175 3975) $PN 156
J 0
(2185 3985);
DISPLAY 0.680851 (2185 3985);
PAINT MONO (2185 3985);
FORCEPROP 0 LASTPIN (2175 4025) $PN 157
J 0
(2185 4035);
DISPLAY 0.680851 (2185 4035);
PAINT MONO (2185 4035);
FORCEPROP 0 LASTPIN (2175 2925) $PN 249
J 0
(2185 2935);
DISPLAY 0.680851 (2185 2935);
PAINT MONO (2185 2935);
FORCEPROP 0 LASTPIN (2175 2975) $PN 250
J 0
(2185 2985);
DISPLAY 0.680851 (2185 2985);
PAINT MONO (2185 2985);
FORCEPROP 0 LASTPIN (2175 4075) $PN 167
J 0
(2185 4085);
DISPLAY 0.680851 (2185 4085);
PAINT MONO (2185 4085);
FORCEPROP 0 LASTPIN (2175 4125) $PN 168
J 0
(2185 4135);
DISPLAY 0.680851 (2185 4135);
PAINT MONO (2185 4135);
FORCEPROP 0 LASTPIN (2175 3025) $PN 260
J 0
(2185 3035);
DISPLAY 0.680851 (2185 3035);
PAINT MONO (2185 3035);
FORCEPROP 0 LASTPIN (2175 3075) $PN 261
J 0
(2185 3085);
DISPLAY 0.680851 (2185 3085);
PAINT MONO (2185 3085);
FORCEPROP 0 LASTPIN (2175 4175) $PN 178
J 0
(2185 4185);
DISPLAY 0.680851 (2185 4185);
PAINT MONO (2185 4185);
FORCEPROP 0 LASTPIN (2175 4225) $PN 179
J 0
(2185 4235);
DISPLAY 0.680851 (2185 4235);
PAINT MONO (2185 4235);
FORCEPROP 0 LASTPIN (2175 3125) $PN 271
J 0
(2185 3135);
DISPLAY 0.680851 (2185 3135);
PAINT MONO (2185 3135);
FORCEPROP 0 LASTPIN (2175 3175) $PN 272
J 0
(2185 3185);
DISPLAY 0.680851 (2185 3185);
PAINT MONO (2185 3185);
FORCEPROP 0 LASTPIN (2175 4275) $PN 189
J 0
(2185 4285);
DISPLAY 0.680851 (2185 4285);
PAINT MONO (2185 4285);
FORCEPROP 0 LASTPIN (2175 4325) $PN 190
J 0
(2185 4335);
DISPLAY 0.680851 (2185 4335);
PAINT MONO (2185 4335);
FORCEPROP 0 LASTPIN (2175 3225) $PN 282
J 0
(2185 3235);
DISPLAY 0.680851 (2185 3235);
PAINT MONO (2185 3235);
FORCEPROP 0 LASTPIN (2175 3275) $PN 283
J 0
(2185 3285);
DISPLAY 0.680851 (2185 3285);
PAINT MONO (2185 3285);
FORCEPROP 0 LASTPIN (2175 4375) $PN 200
J 0
(2185 4385);
DISPLAY 0.680851 (2185 4385);
PAINT MONO (2185 4385);
FORCEPROP 0 LASTPIN (2175 4425) $PN 201
J 0
(2185 4435);
DISPLAY 0.680851 (2185 4435);
PAINT MONO (2185 4435);
FORCEPROP 0 LASTPIN (2175 3325) $PN 94
J 0
(2185 3335);
DISPLAY 0.680851 (2185 3335);
PAINT MONO (2185 3335);
FORCEPROP 0 LASTPIN (2175 3375) $PN 93
J 0
(2185 3385);
DISPLAY 0.680851 (2185 3385);
PAINT MONO (2185 3385);
FORCEPROP 1 LAST NEEDS_NO_SIZE TRUE
J 0
(1425 3425);
DISPLAY 0.723404 (1425 3425);
PAINT GREEN (1425 3425);
DISPLAY INVISIBLE (1425 3425);
FORCEPROP 1 LAST CDS_LMAN_SYM_OUTLINE -600,1150,600,-1150
J 0
(1425 3425);
DISPLAY 0.468085 (1425 3425);
PAINT GREEN (1425 3425);
DISPLAY INVISIBLE (1425 3425);
FORCEPROP 2 LAST CDS_LIB pure_quanta
J 0
(1425 3425);
DISPLAY INVISIBLE (1425 3425);
FORCEPROP 0 LAST $SEC 2
J 0
(825 5000);
DISPLAY 0.680851 (825 5000);
PAINT MONO (825 5000);
DISPLAY INVISIBLE (825 5000);
FORCEPROP 0 LAST CDS_SEC 2
J 0
(825 5000);
DISPLAY 1.021277 (825 5000);
DISPLAY INVISIBLE (825 5000);
FORCEPROP 1 LAST PATH I178
J 0
(1425 3425);
DISPLAY 0.723404 (1425 3425);
PAINT GREEN (1425 3425);
DISPLAY INVISIBLE (1425 3425);
FORCEADD Q_RES..1
(-3050 1725);
FORCEPROP 1 LAST PART_NUMBER CS04992FB07
J 0
(-2950 1700);
DISPLAY 0.404255 (-2950 1700);
DISPLAY INVISIBLE (-2950 1700);
FORCEPROP 1 LAST VALUE 49.9
J 2
(-2825 1725);
DISPLAY 0.510638 (-2825 1725);
FORCEPROP 1 LAST MATERIAL CHIP
J 0
(-3275 1700);
DISPLAY 0.404255 (-3275 1700);
FORCEPROP 1 LAST $LOCATION R3886
J 0
(-3300 1725);
DISPLAY 0.638298 (-3300 1725);
FORCEPROP 1 LASTPIN (-3150 1725) $PN 1
J 0
(-3138 1737);
DISPLAY 0.787234 (-3138 1737);
PAINT MONO (-3138 1737);
FORCEPROP 1 LASTPIN (-2950 1725) $PN 2
J 0
(-2988 1737);
DISPLAY 0.787234 (-2988 1737);
PAINT MONO (-2988 1737);
FORCEPROP 2 LAST CDS_LIB pure_quanta
J 0
(-3050 1725);
DISPLAY INVISIBLE (-3050 1725);
FORCEPROP 1 LAST PACK_TYPE 0402LF
J 0
(-2750 1725);
DISPLAY 0.510638 (-2750 1725);
DISPLAY INVISIBLE (-2750 1725);
FORCEPROP 1 LAST TOLERANCE 1%
J 0
(-2825 1725);
DISPLAY 0.510638 (-2825 1725);
DISPLAY INVISIBLE (-2825 1725);
FORCEPROP 1 LAST WATTAGE 1/16W
J 2
(-2750 1675);
DISPLAY 0.404255 (-2750 1675);
DISPLAY INVISIBLE (-2750 1675);
FORCEPROP 0 LAST CDS_LOCATION R3886
J 0
(-3200 1775);
DISPLAY 1.021277 (-3200 1775);
DISPLAY INVISIBLE (-3200 1775);
FORCEPROP 0 LAST $SEC 1
J 0
(-3200 1775);
DISPLAY 0.680851 (-3200 1775);
PAINT MONO (-3200 1775);
DISPLAY INVISIBLE (-3200 1775);
FORCEPROP 0 LAST CDS_SEC 1
J 0
(-3200 1775);
DISPLAY 1.021277 (-3200 1775);
DISPLAY INVISIBLE (-3200 1775);
FORCEPROP 1 LAST PATH I179
J 0
(-3100 1875);
DISPLAY 0.978723 (-3100 1875);
PAINT WHITE (-3100 1875);
DISPLAY INVISIBLE (-3100 1875);
FORCEADD OFFPAGE..1
(-3000 3175);
FORCEPROP 2 LAST $XR0 25 
J 0
(-3221 3175);
DISPLAY 0.638298 (-3221 3175);
PAINT MONO (-3221 3175);
FORCEPROP 2 LAST CDS_LIB standard
J 0
(-3000 3175);
PAINT MONO (-3000 3175);
DISPLAY INVISIBLE (-3000 3175);
FORCEPROP 1 LAST OFFPAGE TRUE
J 0
(-2675 3050);
DISPLAY 0.872340 (-2675 3050);
DISPLAY INVISIBLE (-2675 3050);
FORCEPROP 1 LAST COMMENT_BODY TRUE
J 0
(-2875 3075);
DISPLAY 0.872340 (-2875 3075);
PAINT GREEN (-2875 3075);
DISPLAY INVISIBLE (-2875 3075);
FORCEPROP 2 LAST PATH I18
J 0
(-2950 3250);
DISPLAY 1.021277 (-2950 3250);
DISPLAY INVISIBLE (-2950 3250);
FORCEADD OFFPAGE..1
(-1825 1675);
FORCEPROP 2 LAST $XR7 97 
J 0
(-2737 1675);
DISPLAY 0.638298 (-2737 1675);
PAINT MONO (-2737 1675);
FORCEPROP 2 LAST $XR6 96 
J 0
(-2647 1675);
DISPLAY 0.638298 (-2647 1675);
PAINT MONO (-2647 1675);
FORCEPROP 2 LAST $XR5 95 
J 0
(-2557 1675);
DISPLAY 0.638298 (-2557 1675);
PAINT MONO (-2557 1675);
FORCEPROP 2 LAST $XR4 94 
J 0
(-2467 1675);
DISPLAY 0.638298 (-2467 1675);
PAINT MONO (-2467 1675);
FORCEPROP 2 LAST $XR3 92 
J 0
(-2377 1675);
DISPLAY 0.638298 (-2377 1675);
PAINT MONO (-2377 1675);
FORCEPROP 2 LAST $XR2 91 
J 0
(-2287 1675);
DISPLAY 0.638298 (-2287 1675);
PAINT MONO (-2287 1675);
FORCEPROP 2 LAST $XR1 90 
J 0
(-2197 1675);
DISPLAY 0.638298 (-2197 1675);
PAINT MONO (-2197 1675);
FORCEPROP 2 LAST $XR0 229 
J 0
(-2107 1675);
DISPLAY 0.638298 (-2107 1675);
PAINT MONO (-2107 1675);
FORCEPROP 2 LAST CDS_LIB standard
J 2
(-1825 1675);
DISPLAY INVISIBLE (-1825 1675);
FORCEPROP 1 LAST OFFPAGE TRUE
J 0
(-1500 1550);
DISPLAY 0.872340 (-1500 1550);
DISPLAY INVISIBLE (-1500 1550);
FORCEPROP 1 LAST COMMENT_BODY TRUE
J 0
(-1700 1575);
DISPLAY 0.872340 (-1700 1575);
PAINT GREEN (-1700 1575);
DISPLAY INVISIBLE (-1700 1575);
FORCEPROP 2 LAST PATH I180
J 2
(-2000 1750);
DISPLAY 1.021277 (-2000 1750);
DISPLAY INVISIBLE (-2000 1750);
FORCEADD OFFPAGE..1
(-3000 3575);
FORCEPROP 2 LAST $XR1 92 
J 0
(-3311 3575);
DISPLAY 0.638298 (-3311 3575);
PAINT MONO (-3311 3575);
FORCEPROP 2 LAST $XR0 25 
J 0
(-3221 3575);
DISPLAY 0.638298 (-3221 3575);
PAINT MONO (-3221 3575);
FORCEPROP 2 LAST CDS_LIB standard
J 0
(-3000 3575);
PAINT MONO (-3000 3575);
DISPLAY INVISIBLE (-3000 3575);
FORCEPROP 1 LAST OFFPAGE TRUE
J 0
(-2675 3450);
DISPLAY 0.872340 (-2675 3450);
DISPLAY INVISIBLE (-2675 3450);
FORCEPROP 1 LAST COMMENT_BODY TRUE
J 0
(-2875 3475);
DISPLAY 0.872340 (-2875 3475);
PAINT GREEN (-2875 3475);
DISPLAY INVISIBLE (-2875 3475);
FORCEPROP 2 LAST PATH I19
J 0
(-2950 3650);
DISPLAY 1.021277 (-2950 3650);
DISPLAY INVISIBLE (-2950 3650);
FORCEADD Q_RES..2
(-1850 275);
FORCEPROP 1 LAST PART_NUMBER CS33572FB01
J 0
(-1810 150);
DISPLAY 0.978723 (-1810 150);
DISPLAY INVISIBLE (-1810 150);
FORCEPROP 1 LAST VALUE 35.7K
J 0
(-1805 350);
DISPLAY 0.978723 (-1805 350);
FORCEPROP 1 LAST TOLERANCE 1%
J 0
(-1805 300);
DISPLAY 0.978723 (-1805 300);
FORCEPROP 1 LAST MATERIAL CHIP
J 0
(-1810 200);
DISPLAY 0.978723 (-1810 200);
FORCEPROP 1 LAST WATTAGE 1/16W
J 0
(-1810 250);
DISPLAY 0.978723 (-1810 250);
FORCEPROP 1 LAST PACK_TYPE 0402LF
J 0
(-1810 100);
DISPLAY 0.978723 (-1810 100);
FORCEPROP 1 LAST $LOCATION R37
J 0
(-1805 400);
DISPLAY 0.978723 (-1805 400);
FORCEPROP 1 LASTPIN (-1850 375) $PN 1
J 0
(-1845 337);
DISPLAY 0.787234 (-1845 337);
FORCEPROP 1 LASTPIN (-1850 175) $PN 2
J 0
(-1845 185);
DISPLAY 0.787234 (-1845 185);
FORCEPROP 2 LAST CDS_LIB pure_quanta
J 0
(-1850 275);
PAINT MONO (-1850 275);
DISPLAY INVISIBLE (-1850 275);
FORCEPROP 2 LAST CDS_LOCATION R37
J 0
(-1800 500);
DISPLAY 1.021277 (-1800 500);
DISPLAY INVISIBLE (-1800 500);
FORCEPROP 2 LAST $SEC 1
J 0
(-1800 500);
DISPLAY 0.680851 (-1800 500);
PAINT MONO (-1800 500);
DISPLAY INVISIBLE (-1800 500);
FORCEPROP 2 LAST CDS_SEC 1
J 0
(-1800 500);
DISPLAY 1.021277 (-1800 500);
DISPLAY INVISIBLE (-1800 500);
FORCEPROP 1 LAST PATH I2
J 0
(-1800 450);
DISPLAY 0.978723 (-1800 450);
PAINT WHITE (-1800 450);
DISPLAY INVISIBLE (-1800 450);
FORCEADD OFFPAGE..1
(-3000 3425);
FORCEPROP 2 LAST $XR0 25 
J 0
(-3221 3425);
DISPLAY 0.638298 (-3221 3425);
PAINT MONO (-3221 3425);
FORCEPROP 2 LAST CDS_LIB standard
J 0
(-3000 3425);
PAINT MONO (-3000 3425);
DISPLAY INVISIBLE (-3000 3425);
FORCEPROP 1 LAST OFFPAGE TRUE
J 0
(-2675 3300);
DISPLAY 0.872340 (-2675 3300);
DISPLAY INVISIBLE (-2675 3300);
FORCEPROP 1 LAST COMMENT_BODY TRUE
J 0
(-2875 3325);
DISPLAY 0.872340 (-2875 3325);
PAINT GREEN (-2875 3325);
DISPLAY INVISIBLE (-2875 3325);
FORCEPROP 2 LAST PATH I20
J 0
(-2950 3500);
DISPLAY 1.021277 (-2950 3500);
DISPLAY INVISIBLE (-2950 3500);
FORCEADD OFFPAGE..1
(-3000 3475);
FORCEPROP 2 LAST $XR0 25 
J 0
(-3221 3475);
DISPLAY 0.638298 (-3221 3475);
PAINT MONO (-3221 3475);
FORCEPROP 2 LAST CDS_LIB standard
J 0
(-3000 3475);
PAINT MONO (-3000 3475);
DISPLAY INVISIBLE (-3000 3475);
FORCEPROP 1 LAST OFFPAGE TRUE
J 0
(-2675 3350);
DISPLAY 0.872340 (-2675 3350);
DISPLAY INVISIBLE (-2675 3350);
FORCEPROP 1 LAST COMMENT_BODY TRUE
J 0
(-2875 3375);
DISPLAY 0.872340 (-2875 3375);
PAINT GREEN (-2875 3375);
DISPLAY INVISIBLE (-2875 3375);
FORCEPROP 2 LAST PATH I21
J 0
(-2950 3550);
DISPLAY 1.021277 (-2950 3550);
DISPLAY INVISIBLE (-2950 3550);
FORCEADD OFFPAGE..1
(-3000 3625);
FORCEPROP 2 LAST $XR1 92 
J 0
(-3311 3625);
DISPLAY 0.638298 (-3311 3625);
PAINT MONO (-3311 3625);
FORCEPROP 2 LAST $XR0 25 
J 0
(-3221 3625);
DISPLAY 0.638298 (-3221 3625);
PAINT MONO (-3221 3625);
FORCEPROP 2 LAST CDS_LIB standard
J 0
(-3000 3625);
PAINT MONO (-3000 3625);
DISPLAY INVISIBLE (-3000 3625);
FORCEPROP 1 LAST OFFPAGE TRUE
J 0
(-2675 3500);
DISPLAY 0.872340 (-2675 3500);
DISPLAY INVISIBLE (-2675 3500);
FORCEPROP 1 LAST COMMENT_BODY TRUE
J 0
(-2875 3525);
DISPLAY 0.872340 (-2875 3525);
PAINT GREEN (-2875 3525);
DISPLAY INVISIBLE (-2875 3525);
FORCEPROP 2 LAST PATH I22
J 0
(-2950 3700);
DISPLAY 1.021277 (-2950 3700);
DISPLAY INVISIBLE (-2950 3700);
FORCEADD OFFPAGE..1
(-3000 4050);
FORCEPROP 2 LAST $XR1 92 
J 0
(-3311 4050);
DISPLAY 0.638298 (-3311 4050);
PAINT MONO (-3311 4050);
FORCEPROP 2 LAST $XR0 25 
J 0
(-3221 4050);
DISPLAY 0.638298 (-3221 4050);
PAINT MONO (-3221 4050);
FORCEPROP 2 LAST CDS_LIB standard
J 0
(-3000 4050);
PAINT MONO (-3000 4050);
DISPLAY INVISIBLE (-3000 4050);
FORCEPROP 1 LAST OFFPAGE TRUE
J 0
(-2675 3925);
DISPLAY 0.872340 (-2675 3925);
DISPLAY INVISIBLE (-2675 3925);
FORCEPROP 1 LAST COMMENT_BODY TRUE
J 0
(-2875 3950);
DISPLAY 0.872340 (-2875 3950);
PAINT GREEN (-2875 3950);
DISPLAY INVISIBLE (-2875 3950);
FORCEPROP 2 LAST PATH I23
J 0
(-2950 4125);
DISPLAY 1.021277 (-2950 4125);
DISPLAY INVISIBLE (-2950 4125);
FORCEADD SCONN288_ADR50017P087CC..1
(-1250 2700);
FORCEPROP 1 LAST PART_NUMBER DFHST8FS460
J 0
(-1695 4710);
DISPLAY 0.723404 (-1695 4710);
PAINT GREEN (-1695 4710);
DISPLAY INVISIBLE (-1695 4710);
FORCEPROP 2 LAST PART_TYPE SMLF
J 0
(-1700 4875);
DISPLAY 1.021277 (-1700 4875);
FORCEPROP 1 LAST MATERIAL IO
J 0
(-1695 4583);
DISPLAY 0.723404 (-1695 4583);
PAINT GREEN (-1695 4583);
FORCEPROP 2 LAST VALUE SCONN288_ADR50017-P087CC
J 0
(-1700 4825);
DISPLAY 1.021277 (-1700 4825);
FORCEPROP 1 LAST $LOCATION J12
J 0
(-1700 4775);
DISPLAY 0.723404 (-1700 4775);
PAINT GREEN (-1700 4775);
FORCEPROP 0 LASTPIN (-1850 2075) $PN 62
J 2
(-1860 2085);
DISPLAY 0.680851 (-1860 2085);
PAINT MONO (-1860 2085);
FORCEPROP 0 LASTPIN (-1850 4125) $PN 66
J 2
(-1860 4135);
DISPLAY 0.680851 (-1860 4135);
PAINT MONO (-1860 4135);
FORCEPROP 0 LASTPIN (-1850 3725) $PN 76
J 2
(-1860 3735);
DISPLAY 0.680851 (-1860 3735);
PAINT MONO (-1860 3735);
FORCEPROP 0 LASTPIN (-1850 4175) $PN 211
J 2
(-1860 4185);
DISPLAY 0.680851 (-1860 4185);
PAINT MONO (-1860 4185);
FORCEPROP 0 LASTPIN (-1850 3775) $PN 221
J 2
(-1860 3785);
DISPLAY 0.680851 (-1860 3785);
PAINT MONO (-1860 3785);
FORCEPROP 0 LASTPIN (-1850 4225) $PN 68
J 2
(-1860 4235);
DISPLAY 0.680851 (-1860 4235);
PAINT MONO (-1860 4235);
FORCEPROP 0 LASTPIN (-1850 3825) $PN 78
J 2
(-1860 3835);
DISPLAY 0.680851 (-1860 3835);
PAINT MONO (-1860 3835);
FORCEPROP 0 LASTPIN (-1850 4275) $PN 213
J 2
(-1860 4285);
DISPLAY 0.680851 (-1860 4285);
PAINT MONO (-1860 4285);
FORCEPROP 0 LASTPIN (-1850 3875) $PN 223
J 2
(-1860 3885);
DISPLAY 0.680851 (-1860 3885);
PAINT MONO (-1860 3885);
FORCEPROP 0 LASTPIN (-1850 4325) $PN 70
J 2
(-1860 4335);
DISPLAY 0.680851 (-1860 4335);
PAINT MONO (-1860 4335);
FORCEPROP 0 LASTPIN (-1850 3925) $PN 80
J 2
(-1860 3935);
DISPLAY 0.680851 (-1860 3935);
PAINT MONO (-1860 3935);
FORCEPROP 0 LASTPIN (-1850 4375) $PN 215
J 2
(-1860 4385);
DISPLAY 0.680851 (-1860 4385);
PAINT MONO (-1860 4385);
FORCEPROP 0 LASTPIN (-1850 3975) $PN 225
J 2
(-1860 3985);
DISPLAY 0.680851 (-1860 3985);
PAINT MONO (-1860 3985);
FORCEPROP 0 LASTPIN (-1850 4425) $PN 72
J 2
(-1860 4435);
DISPLAY 0.680851 (-1860 4435);
PAINT MONO (-1860 4435);
FORCEPROP 0 LASTPIN (-1850 4025) $PN 82
J 2
(-1860 4035);
DISPLAY 0.680851 (-1860 4035);
PAINT MONO (-1860 4035);
FORCEPROP 0 LASTPIN (-1850 2675) $PN 51
J 2
(-1860 2685);
DISPLAY 0.680851 (-1860 2685);
PAINT MONO (-1860 2685);
FORCEPROP 0 LASTPIN (-1850 2225) $PN 96
J 2
(-1860 2235);
DISPLAY 0.680851 (-1860 2235);
PAINT MONO (-1860 2235);
FORCEPROP 0 LASTPIN (-1850 2725) $PN 53
J 2
(-1860 2735);
DISPLAY 0.680851 (-1860 2735);
PAINT MONO (-1860 2735);
FORCEPROP 0 LASTPIN (-1850 2275) $PN 98
J 2
(-1860 2285);
DISPLAY 0.680851 (-1860 2285);
PAINT MONO (-1860 2285);
FORCEPROP 0 LASTPIN (-1850 2775) $PN 196
J 2
(-1860 2785);
DISPLAY 0.680851 (-1860 2785);
PAINT MONO (-1860 2785);
FORCEPROP 0 LASTPIN (-1850 2325) $PN 241
J 2
(-1860 2335);
DISPLAY 0.680851 (-1860 2335);
PAINT MONO (-1860 2335);
FORCEPROP 0 LASTPIN (-1850 2825) $PN 198
J 2
(-1860 2835);
DISPLAY 0.680851 (-1860 2835);
PAINT MONO (-1860 2835);
FORCEPROP 0 LASTPIN (-1850 2375) $PN 243
J 2
(-1860 2385);
DISPLAY 0.680851 (-1860 2385);
PAINT MONO (-1860 2385);
FORCEPROP 0 LASTPIN (-1850 2875) $PN 58
J 2
(-1860 2885);
DISPLAY 0.680851 (-1860 2885);
PAINT MONO (-1860 2885);
FORCEPROP 0 LASTPIN (-1850 2425) $PN 89
J 2
(-1860 2435);
DISPLAY 0.680851 (-1860 2435);
PAINT MONO (-1860 2435);
FORCEPROP 0 LASTPIN (-1850 2925) $PN 60
J 2
(-1860 2935);
DISPLAY 0.680851 (-1860 2935);
PAINT MONO (-1860 2935);
FORCEPROP 0 LASTPIN (-1850 2475) $PN 91
J 2
(-1860 2485);
DISPLAY 0.680851 (-1860 2485);
PAINT MONO (-1860 2485);
FORCEPROP 0 LASTPIN (-1850 2975) $PN 203
J 2
(-1860 2985);
DISPLAY 0.680851 (-1860 2985);
PAINT MONO (-1860 2985);
FORCEPROP 0 LASTPIN (-1850 2525) $PN 234
J 2
(-1860 2535);
DISPLAY 0.680851 (-1860 2535);
PAINT MONO (-1860 2535);
FORCEPROP 0 LASTPIN (-1850 3025) $PN 205
J 2
(-1860 3035);
DISPLAY 0.680851 (-1860 3035);
PAINT MONO (-1860 3035);
FORCEPROP 0 LASTPIN (-1850 2575) $PN 236
J 2
(-1860 2585);
DISPLAY 0.680851 (-1860 2585);
PAINT MONO (-1860 2585);
FORCEPROP 0 LASTPIN (-1850 3125) $PN 218
J 2
(-1860 3135);
DISPLAY 0.680851 (-1860 3135);
PAINT MONO (-1860 3135);
FORCEPROP 0 LASTPIN (-1850 3175) $PN 217
J 2
(-1860 3185);
DISPLAY 0.680851 (-1860 3185);
PAINT MONO (-1860 3185);
FORCEPROP 0 LASTPIN (-1850 3425) $PN 64
J 2
(-1860 3435);
DISPLAY 0.680851 (-1860 3435);
PAINT MONO (-1860 3435);
FORCEPROP 0 LASTPIN (-1850 3275) $PN 84
J 2
(-1860 3285);
DISPLAY 0.680851 (-1860 3285);
PAINT MONO (-1860 3285);
FORCEPROP 0 LASTPIN (-1850 3475) $PN 209
J 2
(-1860 3485);
DISPLAY 0.680851 (-1860 3485);
PAINT MONO (-1860 3485);
FORCEPROP 0 LASTPIN (-1850 3325) $PN 229
J 2
(-1860 3335);
DISPLAY 0.680851 (-1860 3335);
PAINT MONO (-1860 3335);
FORCEPROP 0 LASTPIN (-650 2875) $PN 7
J 0
(-640 2885);
DISPLAY 0.680851 (-640 2885);
PAINT MONO (-640 2885);
FORCEPROP 0 LASTPIN (-650 1225) $PN 100
J 0
(-640 1235);
DISPLAY 0.680851 (-640 1235);
PAINT MONO (-640 1235);
FORCEPROP 0 LASTPIN (-650 2925) $PN 9
J 0
(-640 2935);
DISPLAY 0.680851 (-640 2935);
PAINT MONO (-640 2935);
FORCEPROP 0 LASTPIN (-650 1275) $PN 102
J 0
(-640 1285);
DISPLAY 0.680851 (-640 1285);
PAINT MONO (-640 1285);
FORCEPROP 0 LASTPIN (-650 2975) $PN 152
J 0
(-640 2985);
DISPLAY 0.680851 (-640 2985);
PAINT MONO (-640 2985);
FORCEPROP 0 LASTPIN (-650 1325) $PN 245
J 0
(-640 1335);
DISPLAY 0.680851 (-640 1335);
PAINT MONO (-640 1335);
FORCEPROP 0 LASTPIN (-650 3025) $PN 154
J 0
(-640 3035);
DISPLAY 0.680851 (-640 3035);
PAINT MONO (-640 3035);
FORCEPROP 0 LASTPIN (-650 1375) $PN 247
J 0
(-640 1385);
DISPLAY 0.680851 (-640 1385);
PAINT MONO (-640 1385);
FORCEPROP 0 LASTPIN (-650 3075) $PN 14
J 0
(-640 3085);
DISPLAY 0.680851 (-640 3085);
PAINT MONO (-640 3085);
FORCEPROP 0 LASTPIN (-650 1425) $PN 107
J 0
(-640 1435);
DISPLAY 0.680851 (-640 1435);
PAINT MONO (-640 1435);
FORCEPROP 0 LASTPIN (-650 3125) $PN 16
J 0
(-640 3135);
DISPLAY 0.680851 (-640 3135);
PAINT MONO (-640 3135);
FORCEPROP 0 LASTPIN (-650 1475) $PN 109
J 0
(-640 1485);
DISPLAY 0.680851 (-640 1485);
PAINT MONO (-640 1485);
FORCEPROP 0 LASTPIN (-650 3175) $PN 159
J 0
(-640 3185);
DISPLAY 0.680851 (-640 3185);
PAINT MONO (-640 3185);
FORCEPROP 0 LASTPIN (-650 1525) $PN 252
J 0
(-640 1535);
DISPLAY 0.680851 (-640 1535);
PAINT MONO (-640 1535);
FORCEPROP 0 LASTPIN (-650 3225) $PN 161
J 0
(-640 3235);
DISPLAY 0.680851 (-640 3235);
PAINT MONO (-640 3235);
FORCEPROP 0 LASTPIN (-650 1575) $PN 254
J 0
(-640 1585);
DISPLAY 0.680851 (-640 1585);
PAINT MONO (-640 1585);
FORCEPROP 0 LASTPIN (-650 3275) $PN 18
J 0
(-640 3285);
DISPLAY 0.680851 (-640 3285);
PAINT MONO (-640 3285);
FORCEPROP 0 LASTPIN (-650 1625) $PN 111
J 0
(-640 1635);
DISPLAY 0.680851 (-640 1635);
PAINT MONO (-640 1635);
FORCEPROP 0 LASTPIN (-650 3325) $PN 20
J 0
(-640 3335);
DISPLAY 0.680851 (-640 3335);
PAINT MONO (-640 3335);
FORCEPROP 0 LASTPIN (-650 1675) $PN 113
J 0
(-640 1685);
DISPLAY 0.680851 (-640 1685);
PAINT MONO (-640 1685);
FORCEPROP 0 LASTPIN (-650 3375) $PN 163
J 0
(-640 3385);
DISPLAY 0.680851 (-640 3385);
PAINT MONO (-640 3385);
FORCEPROP 0 LASTPIN (-650 1725) $PN 256
J 0
(-640 1735);
DISPLAY 0.680851 (-640 1735);
PAINT MONO (-640 1735);
FORCEPROP 0 LASTPIN (-650 3425) $PN 165
J 0
(-640 3435);
DISPLAY 0.680851 (-640 3435);
PAINT MONO (-640 3435);
FORCEPROP 0 LASTPIN (-650 1775) $PN 258
J 0
(-640 1785);
DISPLAY 0.680851 (-640 1785);
PAINT MONO (-640 1785);
FORCEPROP 0 LASTPIN (-650 3475) $PN 25
J 0
(-640 3485);
DISPLAY 0.680851 (-640 3485);
PAINT MONO (-640 3485);
FORCEPROP 0 LASTPIN (-650 1825) $PN 118
J 0
(-640 1835);
DISPLAY 0.680851 (-640 1835);
PAINT MONO (-640 1835);
FORCEPROP 0 LASTPIN (-650 3525) $PN 27
J 0
(-640 3535);
DISPLAY 0.680851 (-640 3535);
PAINT MONO (-640 3535);
FORCEPROP 0 LASTPIN (-650 1875) $PN 120
J 0
(-640 1885);
DISPLAY 0.680851 (-640 1885);
PAINT MONO (-640 1885);
FORCEPROP 0 LASTPIN (-650 3575) $PN 170
J 0
(-640 3585);
DISPLAY 0.680851 (-640 3585);
PAINT MONO (-640 3585);
FORCEPROP 0 LASTPIN (-650 1925) $PN 263
J 0
(-640 1935);
DISPLAY 0.680851 (-640 1935);
PAINT MONO (-640 1935);
FORCEPROP 0 LASTPIN (-650 3625) $PN 172
J 0
(-640 3635);
DISPLAY 0.680851 (-640 3635);
PAINT MONO (-640 3635);
FORCEPROP 0 LASTPIN (-650 1975) $PN 265
J 0
(-640 1985);
DISPLAY 0.680851 (-640 1985);
PAINT MONO (-640 1985);
FORCEPROP 0 LASTPIN (-650 3675) $PN 29
J 0
(-640 3685);
DISPLAY 0.680851 (-640 3685);
PAINT MONO (-640 3685);
FORCEPROP 0 LASTPIN (-650 2025) $PN 122
J 0
(-640 2035);
DISPLAY 0.680851 (-640 2035);
PAINT MONO (-640 2035);
FORCEPROP 0 LASTPIN (-650 3725) $PN 31
J 0
(-640 3735);
DISPLAY 0.680851 (-640 3735);
PAINT MONO (-640 3735);
FORCEPROP 0 LASTPIN (-650 2075) $PN 124
J 0
(-640 2085);
DISPLAY 0.680851 (-640 2085);
PAINT MONO (-640 2085);
FORCEPROP 0 LASTPIN (-650 3775) $PN 174
J 0
(-640 3785);
DISPLAY 0.680851 (-640 3785);
PAINT MONO (-640 3785);
FORCEPROP 0 LASTPIN (-650 2125) $PN 267
J 0
(-640 2135);
DISPLAY 0.680851 (-640 2135);
PAINT MONO (-640 2135);
FORCEPROP 0 LASTPIN (-650 3825) $PN 176
J 0
(-640 3835);
DISPLAY 0.680851 (-640 3835);
PAINT MONO (-640 3835);
FORCEPROP 0 LASTPIN (-650 2175) $PN 269
J 0
(-640 2185);
DISPLAY 0.680851 (-640 2185);
PAINT MONO (-640 2185);
FORCEPROP 0 LASTPIN (-650 3875) $PN 36
J 0
(-640 3885);
DISPLAY 0.680851 (-640 3885);
PAINT MONO (-640 3885);
FORCEPROP 0 LASTPIN (-650 2225) $PN 129
J 0
(-640 2235);
DISPLAY 0.680851 (-640 2235);
PAINT MONO (-640 2235);
FORCEPROP 0 LASTPIN (-650 3925) $PN 38
J 0
(-640 3935);
DISPLAY 0.680851 (-640 3935);
PAINT MONO (-640 3935);
FORCEPROP 0 LASTPIN (-650 2275) $PN 131
J 0
(-640 2285);
DISPLAY 0.680851 (-640 2285);
PAINT MONO (-640 2285);
FORCEPROP 0 LASTPIN (-650 3975) $PN 181
J 0
(-640 3985);
DISPLAY 0.680851 (-640 3985);
PAINT MONO (-640 3985);
FORCEPROP 0 LASTPIN (-650 2325) $PN 274
J 0
(-640 2335);
DISPLAY 0.680851 (-640 2335);
PAINT MONO (-640 2335);
FORCEPROP 0 LASTPIN (-650 4025) $PN 183
J 0
(-640 4035);
DISPLAY 0.680851 (-640 4035);
PAINT MONO (-640 4035);
FORCEPROP 0 LASTPIN (-650 2375) $PN 276
J 0
(-640 2385);
DISPLAY 0.680851 (-640 2385);
PAINT MONO (-640 2385);
FORCEPROP 0 LASTPIN (-650 4075) $PN 40
J 0
(-640 4085);
DISPLAY 0.680851 (-640 4085);
PAINT MONO (-640 4085);
FORCEPROP 0 LASTPIN (-650 2425) $PN 133
J 0
(-640 2435);
DISPLAY 0.680851 (-640 2435);
PAINT MONO (-640 2435);
FORCEPROP 0 LASTPIN (-650 4125) $PN 42
J 0
(-640 4135);
DISPLAY 0.680851 (-640 4135);
PAINT MONO (-640 4135);
FORCEPROP 0 LASTPIN (-650 2475) $PN 135
J 0
(-640 2485);
DISPLAY 0.680851 (-640 2485);
PAINT MONO (-640 2485);
FORCEPROP 0 LASTPIN (-650 4175) $PN 185
J 0
(-640 4185);
DISPLAY 0.680851 (-640 4185);
PAINT MONO (-640 4185);
FORCEPROP 0 LASTPIN (-650 2525) $PN 278
J 0
(-640 2535);
DISPLAY 0.680851 (-640 2535);
PAINT MONO (-640 2535);
FORCEPROP 0 LASTPIN (-650 4225) $PN 187
J 0
(-640 4235);
DISPLAY 0.680851 (-640 4235);
PAINT MONO (-640 4235);
FORCEPROP 0 LASTPIN (-650 2575) $PN 280
J 0
(-640 2585);
DISPLAY 0.680851 (-640 2585);
PAINT MONO (-640 2585);
FORCEPROP 0 LASTPIN (-650 4275) $PN 47
J 0
(-640 4285);
DISPLAY 0.680851 (-640 4285);
PAINT MONO (-640 4285);
FORCEPROP 0 LASTPIN (-650 2625) $PN 140
J 0
(-640 2635);
DISPLAY 0.680851 (-640 2635);
PAINT MONO (-640 2635);
FORCEPROP 0 LASTPIN (-650 4325) $PN 49
J 0
(-640 4335);
DISPLAY 0.680851 (-640 4335);
PAINT MONO (-640 4335);
FORCEPROP 0 LASTPIN (-650 2675) $PN 142
J 0
(-640 2685);
DISPLAY 0.680851 (-640 2685);
PAINT MONO (-640 2685);
FORCEPROP 0 LASTPIN (-650 4375) $PN 192
J 0
(-640 4385);
DISPLAY 0.680851 (-640 4385);
PAINT MONO (-640 4385);
FORCEPROP 0 LASTPIN (-650 2725) $PN 285
J 0
(-640 2735);
DISPLAY 0.680851 (-640 2735);
PAINT MONO (-640 2735);
FORCEPROP 0 LASTPIN (-650 4425) $PN 194
J 0
(-640 4435);
DISPLAY 0.680851 (-640 4435);
PAINT MONO (-640 4435);
FORCEPROP 0 LASTPIN (-650 2775) $PN 287
J 0
(-640 2785);
DISPLAY 0.680851 (-640 2785);
PAINT MONO (-640 2785);
FORCEPROP 0 LASTPIN (-1850 1925) $PN 148
J 2
(-1860 1935);
DISPLAY 0.680851 (-1860 1935);
PAINT MONO (-1860 1935);
FORCEPROP 0 LASTPIN (-1850 1825) $PN 4
J 2
(-1860 1835);
DISPLAY 0.680851 (-1860 1835);
PAINT MONO (-1860 1835);
FORCEPROP 0 LASTPIN (-1850 1875) $PN 5
J 2
(-1860 1885);
DISPLAY 0.680851 (-1860 1885);
PAINT MONO (-1860 1885);
FORCEPROP 0 LASTPIN (-1850 1025) $PN 86
J 2
(-1860 1035);
DISPLAY 0.680851 (-1860 1035);
PAINT MONO (-1860 1035);
FORCEPROP 0 LASTPIN (-1850 975) $PN 87
J 2
(-1860 985);
DISPLAY 0.680851 (-1860 985);
PAINT MONO (-1860 985);
FORCEPROP 0 LASTPIN (-1850 3625) $PN 74
J 2
(-1860 3635);
DISPLAY 0.680851 (-1860 3635);
PAINT MONO (-1860 3635);
FORCEPROP 0 LASTPIN (-1850 3575) $PN 227
J 2
(-1860 3585);
DISPLAY 0.680851 (-1860 3585);
PAINT MONO (-1860 3585);
FORCEPROP 0 LASTPIN (-1850 1575) $PN 147
J 2
(-1860 1585);
DISPLAY 0.680851 (-1860 1585);
PAINT MONO (-1860 1585);
FORCEPROP 0 LASTPIN (-1850 2125) $PN 207
J 2
(-1860 2135);
DISPLAY 0.680851 (-1860 2135);
PAINT MONO (-1860 2135);
FORCEPROP 0 LASTPIN (-1850 1175) $PN 2
J 2
(-1860 1185);
DISPLAY 0.680851 (-1860 1185);
PAINT MONO (-1860 1185);
FORCEPROP 0 LASTPIN (-1850 1225) $PN 144
J 2
(-1860 1235);
DISPLAY 0.680851 (-1860 1235);
PAINT MONO (-1860 1235);
FORCEPROP 0 LASTPIN (-1850 1275) $PN 149
J 2
(-1860 1285);
DISPLAY 0.680851 (-1860 1285);
PAINT MONO (-1860 1285);
FORCEPROP 0 LASTPIN (-1850 1325) $PN 150
J 2
(-1860 1335);
DISPLAY 0.680851 (-1860 1335);
PAINT MONO (-1860 1335);
FORCEPROP 0 LASTPIN (-1850 1375) $PN 220
J 2
(-1860 1385);
DISPLAY 0.680851 (-1860 1385);
PAINT MONO (-1860 1385);
FORCEPROP 0 LASTPIN (-1850 1425) $PN 231
J 2
(-1860 1435);
DISPLAY 0.680851 (-1860 1435);
PAINT MONO (-1860 1435);
FORCEPROP 0 LASTPIN (-1850 1475) $PN 232
J 2
(-1860 1485);
DISPLAY 0.680851 (-1860 1485);
PAINT MONO (-1860 1485);
FORCEPROP 0 LASTPIN (-1850 1975) $PN 3
J 2
(-1860 1985);
DISPLAY 0.680851 (-1860 1985);
PAINT MONO (-1860 1985);
FORCEPROP 1 LAST NEEDS_NO_SIZE TRUE
J 0
(-1250 2700);
DISPLAY 0.723404 (-1250 2700);
PAINT GREEN (-1250 2700);
DISPLAY INVISIBLE (-1250 2700);
FORCEPROP 1 LAST CDS_LMAN_SYM_OUTLINE -450,1875,450,-1875
J 0
(-1250 2700);
DISPLAY 0.468085 (-1250 2700);
PAINT GREEN (-1250 2700);
DISPLAY INVISIBLE (-1250 2700);
FORCEPROP 2 LAST CDS_LIB pure_quanta
J 0
(-1250 2700);
DISPLAY INVISIBLE (-1250 2700);
FORCEPROP 2 LAST CDS_LOCATION J12
J 0
(-1700 4925);
DISPLAY 1.021277 (-1700 4925);
DISPLAY INVISIBLE (-1700 4925);
FORCEPROP 0 LAST $SEC 1
J 0
(-1700 4925);
DISPLAY 0.680851 (-1700 4925);
PAINT MONO (-1700 4925);
DISPLAY INVISIBLE (-1700 4925);
FORCEPROP 2 LAST CDS_SEC 1
J 0
(-1700 4925);
DISPLAY 1.021277 (-1700 4925);
DISPLAY INVISIBLE (-1700 4925);
FORCEPROP 1 LAST PATH I24
J 0
(-1250 2700);
DISPLAY 0.723404 (-1250 2700);
PAINT GREEN (-1250 2700);
DISPLAY INVISIBLE (-1250 2700);
FORCEADD TAP..1
R 2
(-2075 2225);
FORCEPROP 3 LASTPIN (-2025 2225) SIG_NAME M_F_CPU0_SB_CB<0>
J 0
(-2015 2235);
DISPLAY 0.659574 (-2015 2235);
PAINT MONO (-2015 2235);
DISPLAY INVISIBLE (-2015 2235);
FORCEPROP 1 LASTPIN (-2025 2225) BN 0
J 2
(-2013 2233);
DISPLAY 0.680851 (-2013 2233);
PAINT GREEN (-2013 2233);
FORCEPROP 2 LAST CDS_LIB standard
J 0
(-2075 2225);
PAINT MONO (-2075 2225);
DISPLAY INVISIBLE (-2075 2225);
FORCEPROP 1 LAST BODY_TYPE PLUMBING
J 2
(-2075 2275);
DISPLAY 0.872340 (-2075 2275);
PAINT GREEN (-2075 2275);
DISPLAY INVISIBLE (-2075 2275);
FORCEPROP 1 LAST HDL_TAP TRUE
J 2
(-2400 2100);
DISPLAY 0.872340 (-2400 2100);
DISPLAY INVISIBLE (-2400 2100);
FORCEPROP 1 LAST PATH I25
J 2
(-2073 2225);
DISPLAY 0.872340 (-2073 2225);
PAINT GREEN (-2073 2225);
DISPLAY INVISIBLE (-2073 2225);
FORCEADD TAP..1
R 2
(-2075 2275);
FORCEPROP 3 LASTPIN (-2025 2275) SIG_NAME M_F_CPU0_SB_CB<1>
J 0
(-2015 2285);
DISPLAY 0.659574 (-2015 2285);
PAINT MONO (-2015 2285);
DISPLAY INVISIBLE (-2015 2285);
FORCEPROP 1 LASTPIN (-2025 2275) BN 1
J 2
(-2013 2283);
DISPLAY 0.680851 (-2013 2283);
PAINT GREEN (-2013 2283);
FORCEPROP 2 LAST CDS_LIB standard
J 0
(-2075 2275);
DISPLAY INVISIBLE (-2075 2275);
FORCEPROP 1 LAST BODY_TYPE PLUMBING
J 2
(-2075 2325);
DISPLAY 0.872340 (-2075 2325);
PAINT GREEN (-2075 2325);
DISPLAY INVISIBLE (-2075 2325);
FORCEPROP 1 LAST HDL_TAP TRUE
J 2
(-2400 2150);
DISPLAY 0.872340 (-2400 2150);
DISPLAY INVISIBLE (-2400 2150);
FORCEPROP 1 LAST PATH I26
J 2
(-2073 2275);
DISPLAY 0.872340 (-2073 2275);
PAINT GREEN (-2073 2275);
DISPLAY INVISIBLE (-2073 2275);
FORCEADD TAP..1
R 2
(-2075 2325);
FORCEPROP 3 LASTPIN (-2025 2325) SIG_NAME M_F_CPU0_SB_CB<2>
J 0
(-2015 2335);
DISPLAY 0.659574 (-2015 2335);
PAINT MONO (-2015 2335);
DISPLAY INVISIBLE (-2015 2335);
FORCEPROP 1 LASTPIN (-2025 2325) BN 2
J 2
(-2013 2333);
DISPLAY 0.680851 (-2013 2333);
PAINT GREEN (-2013 2333);
FORCEPROP 2 LAST CDS_LIB standard
J 0
(-2075 2325);
DISPLAY INVISIBLE (-2075 2325);
FORCEPROP 1 LAST BODY_TYPE PLUMBING
J 2
(-2075 2375);
DISPLAY 0.872340 (-2075 2375);
PAINT GREEN (-2075 2375);
DISPLAY INVISIBLE (-2075 2375);
FORCEPROP 1 LAST HDL_TAP TRUE
J 2
(-2400 2200);
DISPLAY 0.872340 (-2400 2200);
DISPLAY INVISIBLE (-2400 2200);
FORCEPROP 1 LAST PATH I27
J 2
(-2073 2325);
DISPLAY 0.872340 (-2073 2325);
PAINT GREEN (-2073 2325);
DISPLAY INVISIBLE (-2073 2325);
FORCEADD TAP..1
(-425 1225);
FORCEPROP 3 LASTPIN (-475 1225) SIG_NAME M_F_CPU0_SB_DQ<0>
J 0
(-465 1235);
DISPLAY 0.659574 (-465 1235);
PAINT MONO (-465 1235);
DISPLAY INVISIBLE (-465 1235);
FORCEPROP 1 LASTPIN (-475 1225) BN 0
J 0
(-487 1233);
DISPLAY 0.680851 (-487 1233);
PAINT GREEN (-487 1233);
FORCEPROP 2 LAST CDS_LIB standard
J 0
(-425 1225);
PAINT MONO (-425 1225);
DISPLAY INVISIBLE (-425 1225);
FORCEPROP 1 LAST BODY_TYPE PLUMBING
J 0
(-425 1275);
DISPLAY 0.872340 (-425 1275);
PAINT GREEN (-425 1275);
DISPLAY INVISIBLE (-425 1275);
FORCEPROP 1 LAST HDL_TAP TRUE
J 0
(-100 1100);
DISPLAY 0.872340 (-100 1100);
DISPLAY INVISIBLE (-100 1100);
FORCEPROP 1 LAST PATH I28
J 0
(-427 1225);
DISPLAY 0.872340 (-427 1225);
PAINT GREEN (-427 1225);
DISPLAY INVISIBLE (-427 1225);
FORCEADD TAP..1
(-425 1275);
FORCEPROP 3 LASTPIN (-475 1275) SIG_NAME M_F_CPU0_SB_DQ<1>
J 0
(-465 1285);
DISPLAY 0.659574 (-465 1285);
PAINT MONO (-465 1285);
DISPLAY INVISIBLE (-465 1285);
FORCEPROP 1 LASTPIN (-475 1275) BN 1
J 0
(-487 1283);
DISPLAY 0.680851 (-487 1283);
PAINT GREEN (-487 1283);
FORCEPROP 2 LAST CDS_LIB standard
J 0
(-425 1275);
PAINT MONO (-425 1275);
DISPLAY INVISIBLE (-425 1275);
FORCEPROP 1 LAST BODY_TYPE PLUMBING
J 0
(-425 1325);
DISPLAY 0.872340 (-425 1325);
PAINT GREEN (-425 1325);
DISPLAY INVISIBLE (-425 1325);
FORCEPROP 1 LAST HDL_TAP TRUE
J 0
(-100 1150);
DISPLAY 0.872340 (-100 1150);
DISPLAY INVISIBLE (-100 1150);
FORCEPROP 1 LAST PATH I29
J 0
(-427 1275);
DISPLAY 0.872340 (-427 1275);
PAINT GREEN (-427 1275);
DISPLAY INVISIBLE (-427 1275);
FORCEADD OFFPAGE..2
R 2
(-3000 475);
FORCEPROP 2 LAST $XR0 93 
J 0
(-3254 475);
DISPLAY 0.638298 (-3254 475);
PAINT MONO (-3254 475);
FORCEPROP 2 LAST CDS_LIB standard
J 0
(-3000 475);
PAINT MONO (-3000 475);
DISPLAY INVISIBLE (-3000 475);
FORCEPROP 1 LAST OFFPAGE TRUE
J 2
(-3325 350);
DISPLAY 0.872340 (-3325 350);
DISPLAY INVISIBLE (-3325 350);
FORCEPROP 1 LAST COMMENT_BODY TRUE
J 2
(-2955 380);
DISPLAY 0.872340 (-2955 380);
PAINT GREEN (-2955 380);
DISPLAY INVISIBLE (-2955 380);
FORCEPROP 2 LAST PATH I3
J 0
(-2950 550);
DISPLAY 1.021277 (-2950 550);
DISPLAY INVISIBLE (-2950 550);
FORCEADD TAP..1
(-425 1425);
FORCEPROP 3 LASTPIN (-475 1425) SIG_NAME M_F_CPU0_SB_DQ<4>
J 0
(-465 1435);
DISPLAY 0.659574 (-465 1435);
PAINT MONO (-465 1435);
DISPLAY INVISIBLE (-465 1435);
FORCEPROP 1 LASTPIN (-475 1425) BN 4
J 0
(-487 1433);
DISPLAY 0.680851 (-487 1433);
PAINT GREEN (-487 1433);
FORCEPROP 2 LAST CDS_LIB standard
J 0
(-425 1425);
PAINT MONO (-425 1425);
DISPLAY INVISIBLE (-425 1425);
FORCEPROP 1 LAST BODY_TYPE PLUMBING
J 0
(-425 1475);
DISPLAY 0.872340 (-425 1475);
PAINT GREEN (-425 1475);
DISPLAY INVISIBLE (-425 1475);
FORCEPROP 1 LAST HDL_TAP TRUE
J 0
(-100 1300);
DISPLAY 0.872340 (-100 1300);
DISPLAY INVISIBLE (-100 1300);
FORCEPROP 1 LAST PATH I30
J 0
(-427 1425);
DISPLAY 0.872340 (-427 1425);
PAINT GREEN (-427 1425);
DISPLAY INVISIBLE (-427 1425);
FORCEADD TAP..1
(-425 1325);
FORCEPROP 3 LASTPIN (-475 1325) SIG_NAME M_F_CPU0_SB_DQ<2>
J 0
(-465 1335);
DISPLAY 0.659574 (-465 1335);
PAINT MONO (-465 1335);
DISPLAY INVISIBLE (-465 1335);
FORCEPROP 1 LASTPIN (-475 1325) BN 2
J 0
(-487 1333);
DISPLAY 0.680851 (-487 1333);
PAINT GREEN (-487 1333);
FORCEPROP 2 LAST CDS_LIB standard
J 0
(-425 1325);
PAINT MONO (-425 1325);
DISPLAY INVISIBLE (-425 1325);
FORCEPROP 1 LAST BODY_TYPE PLUMBING
J 0
(-425 1375);
DISPLAY 0.872340 (-425 1375);
PAINT GREEN (-425 1375);
DISPLAY INVISIBLE (-425 1375);
FORCEPROP 1 LAST HDL_TAP TRUE
J 0
(-100 1200);
DISPLAY 0.872340 (-100 1200);
DISPLAY INVISIBLE (-100 1200);
FORCEPROP 1 LAST PATH I31
J 0
(-427 1325);
DISPLAY 0.872340 (-427 1325);
PAINT GREEN (-427 1325);
DISPLAY INVISIBLE (-427 1325);
FORCEADD TAP..1
(-425 1375);
FORCEPROP 3 LASTPIN (-475 1375) SIG_NAME M_F_CPU0_SB_DQ<3>
J 0
(-465 1385);
DISPLAY 0.659574 (-465 1385);
PAINT MONO (-465 1385);
DISPLAY INVISIBLE (-465 1385);
FORCEPROP 1 LASTPIN (-475 1375) BN 3
J 0
(-487 1383);
DISPLAY 0.680851 (-487 1383);
PAINT GREEN (-487 1383);
FORCEPROP 2 LAST CDS_LIB standard
J 0
(-425 1375);
PAINT MONO (-425 1375);
DISPLAY INVISIBLE (-425 1375);
FORCEPROP 1 LAST BODY_TYPE PLUMBING
J 0
(-425 1425);
DISPLAY 0.872340 (-425 1425);
PAINT GREEN (-425 1425);
DISPLAY INVISIBLE (-425 1425);
FORCEPROP 1 LAST HDL_TAP TRUE
J 0
(-100 1250);
DISPLAY 0.872340 (-100 1250);
DISPLAY INVISIBLE (-100 1250);
FORCEPROP 1 LAST PATH I32
J 0
(-427 1375);
DISPLAY 0.872340 (-427 1375);
PAINT GREEN (-427 1375);
DISPLAY INVISIBLE (-427 1375);
FORCEADD TAP..1
(-425 1575);
FORCEPROP 3 LASTPIN (-475 1575) SIG_NAME M_F_CPU0_SB_DQ<7>
J 0
(-465 1585);
DISPLAY 0.659574 (-465 1585);
PAINT MONO (-465 1585);
DISPLAY INVISIBLE (-465 1585);
FORCEPROP 1 LASTPIN (-475 1575) BN 7
J 0
(-487 1583);
DISPLAY 0.680851 (-487 1583);
PAINT GREEN (-487 1583);
FORCEPROP 2 LAST CDS_LIB standard
J 0
(-425 1575);
PAINT MONO (-425 1575);
DISPLAY INVISIBLE (-425 1575);
FORCEPROP 1 LAST BODY_TYPE PLUMBING
J 0
(-425 1625);
DISPLAY 0.872340 (-425 1625);
PAINT GREEN (-425 1625);
DISPLAY INVISIBLE (-425 1625);
FORCEPROP 1 LAST HDL_TAP TRUE
J 0
(-100 1450);
DISPLAY 0.872340 (-100 1450);
DISPLAY INVISIBLE (-100 1450);
FORCEPROP 1 LAST PATH I33
J 0
(-427 1575);
DISPLAY 0.872340 (-427 1575);
PAINT GREEN (-427 1575);
DISPLAY INVISIBLE (-427 1575);
FORCEADD TAP..1
(-425 1525);
FORCEPROP 3 LASTPIN (-475 1525) SIG_NAME M_F_CPU0_SB_DQ<6>
J 0
(-465 1535);
DISPLAY 0.659574 (-465 1535);
PAINT MONO (-465 1535);
DISPLAY INVISIBLE (-465 1535);
FORCEPROP 1 LASTPIN (-475 1525) BN 6
J 0
(-487 1533);
DISPLAY 0.680851 (-487 1533);
PAINT GREEN (-487 1533);
FORCEPROP 2 LAST CDS_LIB standard
J 0
(-425 1525);
PAINT MONO (-425 1525);
DISPLAY INVISIBLE (-425 1525);
FORCEPROP 1 LAST BODY_TYPE PLUMBING
J 0
(-425 1575);
DISPLAY 0.872340 (-425 1575);
PAINT GREEN (-425 1575);
DISPLAY INVISIBLE (-425 1575);
FORCEPROP 1 LAST HDL_TAP TRUE
J 0
(-100 1400);
DISPLAY 0.872340 (-100 1400);
DISPLAY INVISIBLE (-100 1400);
FORCEPROP 1 LAST PATH I34
J 0
(-427 1525);
DISPLAY 0.872340 (-427 1525);
PAINT GREEN (-427 1525);
DISPLAY INVISIBLE (-427 1525);
FORCEADD TAP..1
(-425 1475);
FORCEPROP 3 LASTPIN (-475 1475) SIG_NAME M_F_CPU0_SB_DQ<5>
J 0
(-465 1485);
DISPLAY 0.659574 (-465 1485);
PAINT MONO (-465 1485);
DISPLAY INVISIBLE (-465 1485);
FORCEPROP 1 LASTPIN (-475 1475) BN 5
J 0
(-487 1483);
DISPLAY 0.680851 (-487 1483);
PAINT GREEN (-487 1483);
FORCEPROP 2 LAST CDS_LIB standard
J 0
(-425 1475);
PAINT MONO (-425 1475);
DISPLAY INVISIBLE (-425 1475);
FORCEPROP 1 LAST BODY_TYPE PLUMBING
J 0
(-425 1525);
DISPLAY 0.872340 (-425 1525);
PAINT GREEN (-425 1525);
DISPLAY INVISIBLE (-425 1525);
FORCEPROP 1 LAST HDL_TAP TRUE
J 0
(-100 1350);
DISPLAY 0.872340 (-100 1350);
DISPLAY INVISIBLE (-100 1350);
FORCEPROP 1 LAST PATH I35
J 0
(-427 1475);
DISPLAY 0.872340 (-427 1475);
PAINT GREEN (-427 1475);
DISPLAY INVISIBLE (-427 1475);
FORCEADD TAP..1
(-425 1825);
FORCEPROP 3 LASTPIN (-475 1825) SIG_NAME M_F_CPU0_SB_DQ<12>
J 0
(-465 1835);
DISPLAY 0.659574 (-465 1835);
PAINT MONO (-465 1835);
DISPLAY INVISIBLE (-465 1835);
FORCEPROP 1 LASTPIN (-475 1825) BN 12
J 0
(-487 1833);
DISPLAY 0.680851 (-487 1833);
PAINT GREEN (-487 1833);
FORCEPROP 2 LAST CDS_LIB standard
J 0
(-425 1825);
PAINT MONO (-425 1825);
DISPLAY INVISIBLE (-425 1825);
FORCEPROP 1 LAST BODY_TYPE PLUMBING
J 0
(-425 1875);
DISPLAY 0.872340 (-425 1875);
PAINT GREEN (-425 1875);
DISPLAY INVISIBLE (-425 1875);
FORCEPROP 1 LAST HDL_TAP TRUE
J 0
(-100 1700);
DISPLAY 0.872340 (-100 1700);
DISPLAY INVISIBLE (-100 1700);
FORCEPROP 1 LAST PATH I36
J 0
(-427 1825);
DISPLAY 0.872340 (-427 1825);
PAINT GREEN (-427 1825);
DISPLAY INVISIBLE (-427 1825);
FORCEADD TAP..1
(-425 1775);
FORCEPROP 3 LASTPIN (-475 1775) SIG_NAME M_F_CPU0_SB_DQ<11>
J 0
(-465 1785);
DISPLAY 0.659574 (-465 1785);
PAINT MONO (-465 1785);
DISPLAY INVISIBLE (-465 1785);
FORCEPROP 1 LASTPIN (-475 1775) BN 11
J 0
(-487 1783);
DISPLAY 0.680851 (-487 1783);
PAINT GREEN (-487 1783);
FORCEPROP 2 LAST CDS_LIB standard
J 0
(-425 1775);
PAINT MONO (-425 1775);
DISPLAY INVISIBLE (-425 1775);
FORCEPROP 1 LAST BODY_TYPE PLUMBING
J 0
(-425 1825);
DISPLAY 0.872340 (-425 1825);
PAINT GREEN (-425 1825);
DISPLAY INVISIBLE (-425 1825);
FORCEPROP 1 LAST HDL_TAP TRUE
J 0
(-100 1650);
DISPLAY 0.872340 (-100 1650);
DISPLAY INVISIBLE (-100 1650);
FORCEPROP 1 LAST PATH I37
J 0
(-427 1775);
DISPLAY 0.872340 (-427 1775);
PAINT GREEN (-427 1775);
DISPLAY INVISIBLE (-427 1775);
FORCEADD TAP..1
(-425 1725);
FORCEPROP 3 LASTPIN (-475 1725) SIG_NAME M_F_CPU0_SB_DQ<10>
J 0
(-465 1735);
DISPLAY 0.659574 (-465 1735);
PAINT MONO (-465 1735);
DISPLAY INVISIBLE (-465 1735);
FORCEPROP 1 LASTPIN (-475 1725) BN 10
J 0
(-487 1733);
DISPLAY 0.680851 (-487 1733);
PAINT GREEN (-487 1733);
FORCEPROP 2 LAST CDS_LIB standard
J 0
(-425 1725);
PAINT MONO (-425 1725);
DISPLAY INVISIBLE (-425 1725);
FORCEPROP 1 LAST BODY_TYPE PLUMBING
J 0
(-425 1775);
DISPLAY 0.872340 (-425 1775);
PAINT GREEN (-425 1775);
DISPLAY INVISIBLE (-425 1775);
FORCEPROP 1 LAST HDL_TAP TRUE
J 0
(-100 1600);
DISPLAY 0.872340 (-100 1600);
DISPLAY INVISIBLE (-100 1600);
FORCEPROP 1 LAST PATH I38
J 0
(-427 1725);
DISPLAY 0.872340 (-427 1725);
PAINT GREEN (-427 1725);
DISPLAY INVISIBLE (-427 1725);
FORCEADD TAP..1
(-425 1675);
FORCEPROP 3 LASTPIN (-475 1675) SIG_NAME M_F_CPU0_SB_DQ<9>
J 0
(-465 1685);
DISPLAY 0.659574 (-465 1685);
PAINT MONO (-465 1685);
DISPLAY INVISIBLE (-465 1685);
FORCEPROP 1 LASTPIN (-475 1675) BN 9
J 0
(-487 1683);
DISPLAY 0.680851 (-487 1683);
PAINT GREEN (-487 1683);
FORCEPROP 2 LAST CDS_LIB standard
J 0
(-425 1675);
PAINT MONO (-425 1675);
DISPLAY INVISIBLE (-425 1675);
FORCEPROP 1 LAST BODY_TYPE PLUMBING
J 0
(-425 1725);
DISPLAY 0.872340 (-425 1725);
PAINT GREEN (-425 1725);
DISPLAY INVISIBLE (-425 1725);
FORCEPROP 1 LAST HDL_TAP TRUE
J 0
(-100 1550);
DISPLAY 0.872340 (-100 1550);
DISPLAY INVISIBLE (-100 1550);
FORCEPROP 1 LAST PATH I39
J 0
(-427 1675);
DISPLAY 0.872340 (-427 1675);
PAINT GREEN (-427 1675);
DISPLAY INVISIBLE (-427 1675);
FORCEADD OFFPAGE..2
R 2
(-3000 975);
FORCEPROP 2 LAST $XR0 25 
J 0
(-3254 975);
DISPLAY 0.638298 (-3254 975);
PAINT MONO (-3254 975);
FORCEPROP 2 LAST CDS_LIB standard
J 0
(-3000 975);
PAINT MONO (-3000 975);
DISPLAY INVISIBLE (-3000 975);
FORCEPROP 1 LAST OFFPAGE TRUE
J 2
(-3325 850);
DISPLAY 0.872340 (-3325 850);
DISPLAY INVISIBLE (-3325 850);
FORCEPROP 1 LAST COMMENT_BODY TRUE
J 2
(-2955 880);
DISPLAY 0.872340 (-2955 880);
PAINT GREEN (-2955 880);
DISPLAY INVISIBLE (-2955 880);
FORCEPROP 2 LAST PATH I4
J 0
(-2950 1050);
DISPLAY 1.021277 (-2950 1050);
DISPLAY INVISIBLE (-2950 1050);
FORCEADD TAP..1
(-425 1625);
FORCEPROP 3 LASTPIN (-475 1625) SIG_NAME M_F_CPU0_SB_DQ<8>
J 0
(-465 1635);
DISPLAY 0.659574 (-465 1635);
PAINT MONO (-465 1635);
DISPLAY INVISIBLE (-465 1635);
FORCEPROP 1 LASTPIN (-475 1625) BN 8
J 0
(-487 1633);
DISPLAY 0.680851 (-487 1633);
PAINT GREEN (-487 1633);
FORCEPROP 2 LAST CDS_LIB standard
J 0
(-425 1625);
PAINT MONO (-425 1625);
DISPLAY INVISIBLE (-425 1625);
FORCEPROP 1 LAST BODY_TYPE PLUMBING
J 0
(-425 1675);
DISPLAY 0.872340 (-425 1675);
PAINT GREEN (-425 1675);
DISPLAY INVISIBLE (-425 1675);
FORCEPROP 1 LAST HDL_TAP TRUE
J 0
(-100 1500);
DISPLAY 0.872340 (-100 1500);
DISPLAY INVISIBLE (-100 1500);
FORCEPROP 1 LAST PATH I40
J 0
(-427 1625);
DISPLAY 0.872340 (-427 1625);
PAINT GREEN (-427 1625);
DISPLAY INVISIBLE (-427 1625);
FORCEADD TAP..1
(-425 1875);
FORCEPROP 3 LASTPIN (-475 1875) SIG_NAME M_F_CPU0_SB_DQ<13>
J 0
(-465 1885);
DISPLAY 0.659574 (-465 1885);
PAINT MONO (-465 1885);
DISPLAY INVISIBLE (-465 1885);
FORCEPROP 1 LASTPIN (-475 1875) BN 13
J 0
(-487 1883);
DISPLAY 0.680851 (-487 1883);
PAINT GREEN (-487 1883);
FORCEPROP 2 LAST CDS_LIB standard
J 0
(-425 1875);
PAINT MONO (-425 1875);
DISPLAY INVISIBLE (-425 1875);
FORCEPROP 1 LAST BODY_TYPE PLUMBING
J 0
(-425 1925);
DISPLAY 0.872340 (-425 1925);
PAINT GREEN (-425 1925);
DISPLAY INVISIBLE (-425 1925);
FORCEPROP 1 LAST HDL_TAP TRUE
J 0
(-100 1750);
DISPLAY 0.872340 (-100 1750);
DISPLAY INVISIBLE (-100 1750);
FORCEPROP 1 LAST PATH I41
J 0
(-427 1875);
DISPLAY 0.872340 (-427 1875);
PAINT GREEN (-427 1875);
DISPLAY INVISIBLE (-427 1875);
FORCEADD TAP..1
(-425 1925);
FORCEPROP 3 LASTPIN (-475 1925) SIG_NAME M_F_CPU0_SB_DQ<14>
J 0
(-465 1935);
DISPLAY 0.659574 (-465 1935);
PAINT MONO (-465 1935);
DISPLAY INVISIBLE (-465 1935);
FORCEPROP 1 LASTPIN (-475 1925) BN 14
J 0
(-487 1933);
DISPLAY 0.680851 (-487 1933);
PAINT GREEN (-487 1933);
FORCEPROP 2 LAST CDS_LIB standard
J 0
(-425 1925);
PAINT MONO (-425 1925);
DISPLAY INVISIBLE (-425 1925);
FORCEPROP 1 LAST BODY_TYPE PLUMBING
J 0
(-425 1975);
DISPLAY 0.872340 (-425 1975);
PAINT GREEN (-425 1975);
DISPLAY INVISIBLE (-425 1975);
FORCEPROP 1 LAST HDL_TAP TRUE
J 0
(-100 1800);
DISPLAY 0.872340 (-100 1800);
DISPLAY INVISIBLE (-100 1800);
FORCEPROP 1 LAST PATH I42
J 0
(-427 1925);
DISPLAY 0.872340 (-427 1925);
PAINT GREEN (-427 1925);
DISPLAY INVISIBLE (-427 1925);
FORCEADD TAP..1
(-425 1975);
FORCEPROP 3 LASTPIN (-475 1975) SIG_NAME M_F_CPU0_SB_DQ<15>
J 0
(-465 1985);
DISPLAY 0.659574 (-465 1985);
PAINT MONO (-465 1985);
DISPLAY INVISIBLE (-465 1985);
FORCEPROP 1 LASTPIN (-475 1975) BN 15
J 0
(-487 1983);
DISPLAY 0.680851 (-487 1983);
PAINT GREEN (-487 1983);
FORCEPROP 2 LAST CDS_LIB standard
J 0
(-425 1975);
PAINT MONO (-425 1975);
DISPLAY INVISIBLE (-425 1975);
FORCEPROP 1 LAST BODY_TYPE PLUMBING
J 0
(-425 2025);
DISPLAY 0.872340 (-425 2025);
PAINT GREEN (-425 2025);
DISPLAY INVISIBLE (-425 2025);
FORCEPROP 1 LAST HDL_TAP TRUE
J 0
(-100 1850);
DISPLAY 0.872340 (-100 1850);
DISPLAY INVISIBLE (-100 1850);
FORCEPROP 1 LAST PATH I43
J 0
(-427 1975);
DISPLAY 0.872340 (-427 1975);
PAINT GREEN (-427 1975);
DISPLAY INVISIBLE (-427 1975);
FORCEADD TAP..1
(-425 2025);
FORCEPROP 3 LASTPIN (-475 2025) SIG_NAME M_F_CPU0_SB_DQ<16>
J 0
(-465 2035);
DISPLAY 0.659574 (-465 2035);
PAINT MONO (-465 2035);
DISPLAY INVISIBLE (-465 2035);
FORCEPROP 1 LASTPIN (-475 2025) BN 16
J 0
(-487 2033);
DISPLAY 0.680851 (-487 2033);
PAINT GREEN (-487 2033);
FORCEPROP 2 LAST CDS_LIB standard
J 0
(-425 2025);
PAINT MONO (-425 2025);
DISPLAY INVISIBLE (-425 2025);
FORCEPROP 1 LAST BODY_TYPE PLUMBING
J 0
(-425 2075);
DISPLAY 0.872340 (-425 2075);
PAINT GREEN (-425 2075);
DISPLAY INVISIBLE (-425 2075);
FORCEPROP 1 LAST HDL_TAP TRUE
J 0
(-100 1900);
DISPLAY 0.872340 (-100 1900);
DISPLAY INVISIBLE (-100 1900);
FORCEPROP 1 LAST PATH I44
J 0
(-427 2025);
DISPLAY 0.872340 (-427 2025);
PAINT GREEN (-427 2025);
DISPLAY INVISIBLE (-427 2025);
FORCEADD TAP..1
(-425 2075);
FORCEPROP 3 LASTPIN (-475 2075) SIG_NAME M_F_CPU0_SB_DQ<17>
J 0
(-465 2085);
DISPLAY 0.659574 (-465 2085);
PAINT MONO (-465 2085);
DISPLAY INVISIBLE (-465 2085);
FORCEPROP 1 LASTPIN (-475 2075) BN 17
J 0
(-487 2083);
DISPLAY 0.680851 (-487 2083);
PAINT GREEN (-487 2083);
FORCEPROP 2 LAST CDS_LIB standard
J 0
(-425 2075);
PAINT MONO (-425 2075);
DISPLAY INVISIBLE (-425 2075);
FORCEPROP 1 LAST BODY_TYPE PLUMBING
J 0
(-425 2125);
DISPLAY 0.872340 (-425 2125);
PAINT GREEN (-425 2125);
DISPLAY INVISIBLE (-425 2125);
FORCEPROP 1 LAST HDL_TAP TRUE
J 0
(-100 1950);
DISPLAY 0.872340 (-100 1950);
DISPLAY INVISIBLE (-100 1950);
FORCEPROP 1 LAST PATH I45
J 0
(-427 2075);
DISPLAY 0.872340 (-427 2075);
PAINT GREEN (-427 2075);
DISPLAY INVISIBLE (-427 2075);
FORCEADD TAP..1
(-425 2325);
FORCEPROP 3 LASTPIN (-475 2325) SIG_NAME M_F_CPU0_SB_DQ<22>
J 0
(-465 2335);
DISPLAY 0.659574 (-465 2335);
PAINT MONO (-465 2335);
DISPLAY INVISIBLE (-465 2335);
FORCEPROP 1 LASTPIN (-475 2325) BN 22
J 0
(-487 2333);
DISPLAY 0.680851 (-487 2333);
PAINT GREEN (-487 2333);
FORCEPROP 2 LAST CDS_LIB standard
J 0
(-425 2325);
DISPLAY INVISIBLE (-425 2325);
FORCEPROP 1 LAST BODY_TYPE PLUMBING
J 0
(-425 2375);
DISPLAY 0.872340 (-425 2375);
PAINT GREEN (-425 2375);
DISPLAY INVISIBLE (-425 2375);
FORCEPROP 1 LAST HDL_TAP TRUE
J 0
(-100 2200);
DISPLAY 0.872340 (-100 2200);
DISPLAY INVISIBLE (-100 2200);
FORCEPROP 1 LAST PATH I46
J 0
(-427 2325);
DISPLAY 0.872340 (-427 2325);
PAINT GREEN (-427 2325);
DISPLAY INVISIBLE (-427 2325);
FORCEADD TAP..1
(-425 2275);
FORCEPROP 3 LASTPIN (-475 2275) SIG_NAME M_F_CPU0_SB_DQ<21>
J 0
(-465 2285);
DISPLAY 0.659574 (-465 2285);
PAINT MONO (-465 2285);
DISPLAY INVISIBLE (-465 2285);
FORCEPROP 1 LASTPIN (-475 2275) BN 21
J 0
(-487 2283);
DISPLAY 0.680851 (-487 2283);
PAINT GREEN (-487 2283);
FORCEPROP 2 LAST CDS_LIB standard
J 0
(-425 2275);
PAINT MONO (-425 2275);
DISPLAY INVISIBLE (-425 2275);
FORCEPROP 1 LAST BODY_TYPE PLUMBING
J 0
(-425 2325);
DISPLAY 0.872340 (-425 2325);
PAINT GREEN (-425 2325);
DISPLAY INVISIBLE (-425 2325);
FORCEPROP 1 LAST HDL_TAP TRUE
J 0
(-100 2150);
DISPLAY 0.872340 (-100 2150);
DISPLAY INVISIBLE (-100 2150);
FORCEPROP 1 LAST PATH I47
J 0
(-427 2275);
DISPLAY 0.872340 (-427 2275);
PAINT GREEN (-427 2275);
DISPLAY INVISIBLE (-427 2275);
FORCEADD TAP..1
(-425 2225);
FORCEPROP 3 LASTPIN (-475 2225) SIG_NAME M_F_CPU0_SB_DQ<20>
J 0
(-465 2235);
DISPLAY 0.659574 (-465 2235);
PAINT MONO (-465 2235);
DISPLAY INVISIBLE (-465 2235);
FORCEPROP 1 LASTPIN (-475 2225) BN 20
J 0
(-487 2233);
DISPLAY 0.680851 (-487 2233);
PAINT GREEN (-487 2233);
FORCEPROP 2 LAST CDS_LIB standard
J 0
(-425 2225);
PAINT MONO (-425 2225);
DISPLAY INVISIBLE (-425 2225);
FORCEPROP 1 LAST BODY_TYPE PLUMBING
J 0
(-425 2275);
DISPLAY 0.872340 (-425 2275);
PAINT GREEN (-425 2275);
DISPLAY INVISIBLE (-425 2275);
FORCEPROP 1 LAST HDL_TAP TRUE
J 0
(-100 2100);
DISPLAY 0.872340 (-100 2100);
DISPLAY INVISIBLE (-100 2100);
FORCEPROP 1 LAST PATH I48
J 0
(-427 2225);
DISPLAY 0.872340 (-427 2225);
PAINT GREEN (-427 2225);
DISPLAY INVISIBLE (-427 2225);
FORCEADD TAP..1
(-425 2175);
FORCEPROP 3 LASTPIN (-475 2175) SIG_NAME M_F_CPU0_SB_DQ<19>
J 0
(-465 2185);
DISPLAY 0.659574 (-465 2185);
PAINT MONO (-465 2185);
DISPLAY INVISIBLE (-465 2185);
FORCEPROP 1 LASTPIN (-475 2175) BN 19
J 0
(-487 2183);
DISPLAY 0.680851 (-487 2183);
PAINT GREEN (-487 2183);
FORCEPROP 2 LAST CDS_LIB standard
J 0
(-425 2175);
PAINT MONO (-425 2175);
DISPLAY INVISIBLE (-425 2175);
FORCEPROP 1 LAST BODY_TYPE PLUMBING
J 0
(-425 2225);
DISPLAY 0.872340 (-425 2225);
PAINT GREEN (-425 2225);
DISPLAY INVISIBLE (-425 2225);
FORCEPROP 1 LAST HDL_TAP TRUE
J 0
(-100 2050);
DISPLAY 0.872340 (-100 2050);
DISPLAY INVISIBLE (-100 2050);
FORCEPROP 1 LAST PATH I49
J 0
(-427 2175);
DISPLAY 0.872340 (-427 2175);
PAINT GREEN (-427 2175);
DISPLAY INVISIBLE (-427 2175);
FORCEADD OFFPAGE..2
R 2
(-3000 1025);
FORCEPROP 2 LAST $XR0 25 
J 0
(-3254 1025);
DISPLAY 0.638298 (-3254 1025);
PAINT MONO (-3254 1025);
FORCEPROP 2 LAST CDS_LIB standard
J 0
(-3000 1025);
PAINT MONO (-3000 1025);
DISPLAY INVISIBLE (-3000 1025);
FORCEPROP 1 LAST OFFPAGE TRUE
J 2
(-3325 900);
DISPLAY 0.872340 (-3325 900);
DISPLAY INVISIBLE (-3325 900);
FORCEPROP 1 LAST COMMENT_BODY TRUE
J 2
(-2955 930);
DISPLAY 0.872340 (-2955 930);
PAINT GREEN (-2955 930);
DISPLAY INVISIBLE (-2955 930);
FORCEPROP 2 LAST PATH I5
J 0
(-2950 1100);
DISPLAY 1.021277 (-2950 1100);
DISPLAY INVISIBLE (-2950 1100);
FORCEADD TAP..1
(-425 2125);
FORCEPROP 3 LASTPIN (-475 2125) SIG_NAME M_F_CPU0_SB_DQ<18>
J 0
(-465 2135);
DISPLAY 0.659574 (-465 2135);
PAINT MONO (-465 2135);
DISPLAY INVISIBLE (-465 2135);
FORCEPROP 1 LASTPIN (-475 2125) BN 18
J 0
(-487 2133);
DISPLAY 0.680851 (-487 2133);
PAINT GREEN (-487 2133);
FORCEPROP 2 LAST CDS_LIB standard
J 0
(-425 2125);
PAINT MONO (-425 2125);
DISPLAY INVISIBLE (-425 2125);
FORCEPROP 1 LAST BODY_TYPE PLUMBING
J 0
(-425 2175);
DISPLAY 0.872340 (-425 2175);
PAINT GREEN (-425 2175);
DISPLAY INVISIBLE (-425 2175);
FORCEPROP 1 LAST HDL_TAP TRUE
J 0
(-100 2000);
DISPLAY 0.872340 (-100 2000);
DISPLAY INVISIBLE (-100 2000);
FORCEPROP 1 LAST PATH I50
J 0
(-427 2125);
DISPLAY 0.872340 (-427 2125);
PAINT GREEN (-427 2125);
DISPLAY INVISIBLE (-427 2125);
FORCEADD TAP..1
R 2
(-2075 2375);
FORCEPROP 3 LASTPIN (-2025 2375) SIG_NAME M_F_CPU0_SB_CB<3>
J 0
(-2015 2385);
DISPLAY 0.659574 (-2015 2385);
PAINT MONO (-2015 2385);
DISPLAY INVISIBLE (-2015 2385);
FORCEPROP 1 LASTPIN (-2025 2375) BN 3
J 2
(-2013 2383);
DISPLAY 0.680851 (-2013 2383);
PAINT GREEN (-2013 2383);
FORCEPROP 2 LAST CDS_LIB standard
J 0
(-2075 2375);
DISPLAY INVISIBLE (-2075 2375);
FORCEPROP 1 LAST BODY_TYPE PLUMBING
J 2
(-2075 2425);
DISPLAY 0.872340 (-2075 2425);
PAINT GREEN (-2075 2425);
DISPLAY INVISIBLE (-2075 2425);
FORCEPROP 1 LAST HDL_TAP TRUE
J 2
(-2400 2250);
DISPLAY 0.872340 (-2400 2250);
DISPLAY INVISIBLE (-2400 2250);
FORCEPROP 1 LAST PATH I51
J 2
(-2073 2375);
DISPLAY 0.872340 (-2073 2375);
PAINT GREEN (-2073 2375);
DISPLAY INVISIBLE (-2073 2375);
FORCEADD TAP..1
R 2
(-2075 2425);
FORCEPROP 3 LASTPIN (-2025 2425) SIG_NAME M_F_CPU0_SB_CB<4>
J 0
(-2015 2435);
DISPLAY 0.659574 (-2015 2435);
PAINT MONO (-2015 2435);
DISPLAY INVISIBLE (-2015 2435);
FORCEPROP 1 LASTPIN (-2025 2425) BN 4
J 2
(-2013 2433);
DISPLAY 0.680851 (-2013 2433);
PAINT GREEN (-2013 2433);
FORCEPROP 2 LAST CDS_LIB standard
J 0
(-2075 2425);
DISPLAY INVISIBLE (-2075 2425);
FORCEPROP 1 LAST BODY_TYPE PLUMBING
J 2
(-2075 2475);
DISPLAY 0.872340 (-2075 2475);
PAINT GREEN (-2075 2475);
DISPLAY INVISIBLE (-2075 2475);
FORCEPROP 1 LAST HDL_TAP TRUE
J 2
(-2400 2300);
DISPLAY 0.872340 (-2400 2300);
DISPLAY INVISIBLE (-2400 2300);
FORCEPROP 1 LAST PATH I52
J 2
(-2073 2425);
DISPLAY 0.872340 (-2073 2425);
PAINT GREEN (-2073 2425);
DISPLAY INVISIBLE (-2073 2425);
FORCEADD TAP..1
R 2
(-2075 2475);
FORCEPROP 3 LASTPIN (-2025 2475) SIG_NAME M_F_CPU0_SB_CB<5>
J 0
(-2015 2485);
DISPLAY 0.659574 (-2015 2485);
PAINT MONO (-2015 2485);
DISPLAY INVISIBLE (-2015 2485);
FORCEPROP 1 LASTPIN (-2025 2475) BN 5
J 2
(-2013 2483);
DISPLAY 0.680851 (-2013 2483);
PAINT GREEN (-2013 2483);
FORCEPROP 2 LAST CDS_LIB standard
J 0
(-2075 2475);
DISPLAY INVISIBLE (-2075 2475);
FORCEPROP 1 LAST BODY_TYPE PLUMBING
J 2
(-2075 2525);
DISPLAY 0.872340 (-2075 2525);
PAINT GREEN (-2075 2525);
DISPLAY INVISIBLE (-2075 2525);
FORCEPROP 1 LAST HDL_TAP TRUE
J 2
(-2400 2350);
DISPLAY 0.872340 (-2400 2350);
DISPLAY INVISIBLE (-2400 2350);
FORCEPROP 1 LAST PATH I53
J 2
(-2073 2475);
DISPLAY 0.872340 (-2073 2475);
PAINT GREEN (-2073 2475);
DISPLAY INVISIBLE (-2073 2475);
FORCEADD TAP..1
R 2
(-2075 2575);
FORCEPROP 3 LASTPIN (-2025 2575) SIG_NAME M_F_CPU0_SB_CB<7>
J 0
(-2015 2585);
DISPLAY 0.659574 (-2015 2585);
PAINT MONO (-2015 2585);
DISPLAY INVISIBLE (-2015 2585);
FORCEPROP 1 LASTPIN (-2025 2575) BN 7
J 2
(-2013 2583);
DISPLAY 0.680851 (-2013 2583);
PAINT GREEN (-2013 2583);
FORCEPROP 2 LAST CDS_LIB standard
J 0
(-2075 2575);
DISPLAY INVISIBLE (-2075 2575);
FORCEPROP 1 LAST BODY_TYPE PLUMBING
J 2
(-2075 2625);
DISPLAY 0.872340 (-2075 2625);
PAINT GREEN (-2075 2625);
DISPLAY INVISIBLE (-2075 2625);
FORCEPROP 1 LAST HDL_TAP TRUE
J 2
(-2400 2450);
DISPLAY 0.872340 (-2400 2450);
DISPLAY INVISIBLE (-2400 2450);
FORCEPROP 1 LAST PATH I54
J 2
(-2073 2575);
DISPLAY 0.872340 (-2073 2575);
PAINT GREEN (-2073 2575);
DISPLAY INVISIBLE (-2073 2575);
FORCEADD TAP..1
R 2
(-2075 2525);
FORCEPROP 3 LASTPIN (-2025 2525) SIG_NAME M_F_CPU0_SB_CB<6>
J 0
(-2015 2535);
DISPLAY 0.659574 (-2015 2535);
PAINT MONO (-2015 2535);
DISPLAY INVISIBLE (-2015 2535);
FORCEPROP 1 LASTPIN (-2025 2525) BN 6
J 2
(-2013 2533);
DISPLAY 0.680851 (-2013 2533);
PAINT GREEN (-2013 2533);
FORCEPROP 2 LAST CDS_LIB standard
J 0
(-2075 2525);
DISPLAY INVISIBLE (-2075 2525);
FORCEPROP 1 LAST BODY_TYPE PLUMBING
J 2
(-2075 2575);
DISPLAY 0.872340 (-2075 2575);
PAINT GREEN (-2075 2575);
DISPLAY INVISIBLE (-2075 2575);
FORCEPROP 1 LAST HDL_TAP TRUE
J 2
(-2400 2400);
DISPLAY 0.872340 (-2400 2400);
DISPLAY INVISIBLE (-2400 2400);
FORCEPROP 1 LAST PATH I55
J 2
(-2073 2525);
DISPLAY 0.872340 (-2073 2525);
PAINT GREEN (-2073 2525);
DISPLAY INVISIBLE (-2073 2525);
FORCEADD TAP..1
R 2
(-2075 2675);
FORCEPROP 3 LASTPIN (-2025 2675) SIG_NAME M_F_CPU0_SA_CB<0>
J 0
(-2015 2685);
DISPLAY 0.659574 (-2015 2685);
PAINT MONO (-2015 2685);
DISPLAY INVISIBLE (-2015 2685);
FORCEPROP 1 LASTPIN (-2025 2675) BN 0
J 2
(-2013 2683);
DISPLAY 0.680851 (-2013 2683);
PAINT GREEN (-2013 2683);
FORCEPROP 2 LAST CDS_LIB standard
J 0
(-2075 2675);
PAINT MONO (-2075 2675);
DISPLAY INVISIBLE (-2075 2675);
FORCEPROP 1 LAST BODY_TYPE PLUMBING
J 2
(-2075 2725);
DISPLAY 0.872340 (-2075 2725);
PAINT GREEN (-2075 2725);
DISPLAY INVISIBLE (-2075 2725);
FORCEPROP 1 LAST HDL_TAP TRUE
J 2
(-2400 2550);
DISPLAY 0.872340 (-2400 2550);
DISPLAY INVISIBLE (-2400 2550);
FORCEPROP 1 LAST PATH I56
J 2
(-2073 2675);
DISPLAY 0.872340 (-2073 2675);
PAINT GREEN (-2073 2675);
DISPLAY INVISIBLE (-2073 2675);
FORCEADD TAP..1
R 2
(-2075 2825);
FORCEPROP 3 LASTPIN (-2025 2825) SIG_NAME M_F_CPU0_SA_CB<3>
J 0
(-2015 2835);
DISPLAY 0.659574 (-2015 2835);
PAINT MONO (-2015 2835);
DISPLAY INVISIBLE (-2015 2835);
FORCEPROP 1 LASTPIN (-2025 2825) BN 3
J 2
(-2013 2833);
DISPLAY 0.680851 (-2013 2833);
PAINT GREEN (-2013 2833);
FORCEPROP 2 LAST CDS_LIB standard
J 0
(-2075 2825);
DISPLAY INVISIBLE (-2075 2825);
FORCEPROP 1 LAST BODY_TYPE PLUMBING
J 2
(-2075 2875);
DISPLAY 0.872340 (-2075 2875);
PAINT GREEN (-2075 2875);
DISPLAY INVISIBLE (-2075 2875);
FORCEPROP 1 LAST HDL_TAP TRUE
J 2
(-2400 2700);
DISPLAY 0.872340 (-2400 2700);
DISPLAY INVISIBLE (-2400 2700);
FORCEPROP 1 LAST PATH I57
J 2
(-2073 2825);
DISPLAY 0.872340 (-2073 2825);
PAINT GREEN (-2073 2825);
DISPLAY INVISIBLE (-2073 2825);
FORCEADD TAP..1
R 2
(-2075 2775);
FORCEPROP 3 LASTPIN (-2025 2775) SIG_NAME M_F_CPU0_SA_CB<2>
J 0
(-2015 2785);
DISPLAY 0.659574 (-2015 2785);
PAINT MONO (-2015 2785);
DISPLAY INVISIBLE (-2015 2785);
FORCEPROP 1 LASTPIN (-2025 2775) BN 2
J 2
(-2013 2783);
DISPLAY 0.680851 (-2013 2783);
PAINT GREEN (-2013 2783);
FORCEPROP 2 LAST CDS_LIB standard
J 0
(-2075 2775);
DISPLAY INVISIBLE (-2075 2775);
FORCEPROP 1 LAST BODY_TYPE PLUMBING
J 2
(-2075 2825);
DISPLAY 0.872340 (-2075 2825);
PAINT GREEN (-2075 2825);
DISPLAY INVISIBLE (-2075 2825);
FORCEPROP 1 LAST HDL_TAP TRUE
J 2
(-2400 2650);
DISPLAY 0.872340 (-2400 2650);
DISPLAY INVISIBLE (-2400 2650);
FORCEPROP 1 LAST PATH I58
J 2
(-2073 2775);
DISPLAY 0.872340 (-2073 2775);
PAINT GREEN (-2073 2775);
DISPLAY INVISIBLE (-2073 2775);
FORCEADD TAP..1
R 2
(-2075 2725);
FORCEPROP 3 LASTPIN (-2025 2725) SIG_NAME M_F_CPU0_SA_CB<1>
J 0
(-2015 2735);
DISPLAY 0.659574 (-2015 2735);
PAINT MONO (-2015 2735);
DISPLAY INVISIBLE (-2015 2735);
FORCEPROP 1 LASTPIN (-2025 2725) BN 1
J 2
(-2013 2733);
DISPLAY 0.680851 (-2013 2733);
PAINT GREEN (-2013 2733);
FORCEPROP 2 LAST CDS_LIB standard
J 0
(-2075 2725);
DISPLAY INVISIBLE (-2075 2725);
FORCEPROP 1 LAST BODY_TYPE PLUMBING
J 2
(-2075 2775);
DISPLAY 0.872340 (-2075 2775);
PAINT GREEN (-2075 2775);
DISPLAY INVISIBLE (-2075 2775);
FORCEPROP 1 LAST HDL_TAP TRUE
J 2
(-2400 2600);
DISPLAY 0.872340 (-2400 2600);
DISPLAY INVISIBLE (-2400 2600);
FORCEPROP 1 LAST PATH I59
J 2
(-2073 2725);
DISPLAY 0.872340 (-2073 2725);
PAINT GREEN (-2073 2725);
DISPLAY INVISIBLE (-2073 2725);
FORCEADD OFFPAGE..3
R 2
(-3000 1575);
FORCEPROP 2 LAST $XR0 114 
J 0
(-3280 1575);
DISPLAY 0.638298 (-3280 1575);
PAINT MONO (-3280 1575);
FORCEPROP 2 LAST CDS_LIB standard
J 0
(-3000 1575);
PAINT MONO (-3000 1575);
DISPLAY INVISIBLE (-3000 1575);
FORCEPROP 1 LAST OFFPAGE TRUE
J 2
(-3325 1450);
DISPLAY 0.872340 (-3325 1450);
DISPLAY INVISIBLE (-3325 1450);
FORCEPROP 1 LAST COMMENT_BODY TRUE
J 2
(-2950 1475);
DISPLAY 0.872340 (-2950 1475);
PAINT GREEN (-2950 1475);
DISPLAY INVISIBLE (-2950 1475);
FORCEPROP 2 LAST PATH I6
J 0
(-2950 1650);
DISPLAY 1.021277 (-2950 1650);
DISPLAY INVISIBLE (-2950 1650);
FORCEADD TAP..1
R 2
(-2075 2925);
FORCEPROP 3 LASTPIN (-2025 2925) SIG_NAME M_F_CPU0_SA_CB<5>
J 0
(-2015 2935);
DISPLAY 0.659574 (-2015 2935);
PAINT MONO (-2015 2935);
DISPLAY INVISIBLE (-2015 2935);
FORCEPROP 1 LASTPIN (-2025 2925) BN 5
J 2
(-2013 2933);
DISPLAY 0.680851 (-2013 2933);
PAINT GREEN (-2013 2933);
FORCEPROP 2 LAST CDS_LIB standard
J 0
(-2075 2925);
DISPLAY INVISIBLE (-2075 2925);
FORCEPROP 1 LAST BODY_TYPE PLUMBING
J 2
(-2075 2975);
DISPLAY 0.872340 (-2075 2975);
PAINT GREEN (-2075 2975);
DISPLAY INVISIBLE (-2075 2975);
FORCEPROP 1 LAST HDL_TAP TRUE
J 2
(-2400 2800);
DISPLAY 0.872340 (-2400 2800);
DISPLAY INVISIBLE (-2400 2800);
FORCEPROP 1 LAST PATH I60
J 2
(-2073 2925);
DISPLAY 0.872340 (-2073 2925);
PAINT GREEN (-2073 2925);
DISPLAY INVISIBLE (-2073 2925);
FORCEADD TAP..1
R 2
(-2075 3025);
FORCEPROP 3 LASTPIN (-2025 3025) SIG_NAME M_F_CPU0_SA_CB<7>
J 0
(-2015 3035);
DISPLAY 0.659574 (-2015 3035);
PAINT MONO (-2015 3035);
DISPLAY INVISIBLE (-2015 3035);
FORCEPROP 1 LASTPIN (-2025 3025) BN 7
J 2
(-2013 3033);
DISPLAY 0.680851 (-2013 3033);
PAINT GREEN (-2013 3033);
FORCEPROP 2 LAST CDS_LIB standard
J 0
(-2075 3025);
DISPLAY INVISIBLE (-2075 3025);
FORCEPROP 1 LAST BODY_TYPE PLUMBING
J 2
(-2075 3075);
DISPLAY 0.872340 (-2075 3075);
PAINT GREEN (-2075 3075);
DISPLAY INVISIBLE (-2075 3075);
FORCEPROP 1 LAST HDL_TAP TRUE
J 2
(-2400 2900);
DISPLAY 0.872340 (-2400 2900);
DISPLAY INVISIBLE (-2400 2900);
FORCEPROP 1 LAST PATH I61
J 2
(-2073 3025);
DISPLAY 0.872340 (-2073 3025);
PAINT GREEN (-2073 3025);
DISPLAY INVISIBLE (-2073 3025);
FORCEADD TAP..1
R 2
(-2075 2975);
FORCEPROP 3 LASTPIN (-2025 2975) SIG_NAME M_F_CPU0_SA_CB<6>
J 0
(-2015 2985);
DISPLAY 0.659574 (-2015 2985);
PAINT MONO (-2015 2985);
DISPLAY INVISIBLE (-2015 2985);
FORCEPROP 1 LASTPIN (-2025 2975) BN 6
J 2
(-2013 2983);
DISPLAY 0.680851 (-2013 2983);
PAINT GREEN (-2013 2983);
FORCEPROP 2 LAST CDS_LIB standard
J 0
(-2075 2975);
DISPLAY INVISIBLE (-2075 2975);
FORCEPROP 1 LAST BODY_TYPE PLUMBING
J 2
(-2075 3025);
DISPLAY 0.872340 (-2075 3025);
PAINT GREEN (-2075 3025);
DISPLAY INVISIBLE (-2075 3025);
FORCEPROP 1 LAST HDL_TAP TRUE
J 2
(-2400 2850);
DISPLAY 0.872340 (-2400 2850);
DISPLAY INVISIBLE (-2400 2850);
FORCEPROP 1 LAST PATH I62
J 2
(-2073 2975);
DISPLAY 0.872340 (-2073 2975);
PAINT GREEN (-2073 2975);
DISPLAY INVISIBLE (-2073 2975);
FORCEADD TAP..1
R 2
(-2075 2875);
FORCEPROP 3 LASTPIN (-2025 2875) SIG_NAME M_F_CPU0_SA_CB<4>
J 0
(-2015 2885);
DISPLAY 0.659574 (-2015 2885);
PAINT MONO (-2015 2885);
DISPLAY INVISIBLE (-2015 2885);
FORCEPROP 1 LASTPIN (-2025 2875) BN 4
J 2
(-2013 2883);
DISPLAY 0.680851 (-2013 2883);
PAINT GREEN (-2013 2883);
FORCEPROP 2 LAST CDS_LIB standard
J 0
(-2075 2875);
DISPLAY INVISIBLE (-2075 2875);
FORCEPROP 1 LAST BODY_TYPE PLUMBING
J 2
(-2075 2925);
DISPLAY 0.872340 (-2075 2925);
PAINT GREEN (-2075 2925);
DISPLAY INVISIBLE (-2075 2925);
FORCEPROP 1 LAST HDL_TAP TRUE
J 2
(-2400 2750);
DISPLAY 0.872340 (-2400 2750);
DISPLAY INVISIBLE (-2400 2750);
FORCEPROP 1 LAST PATH I63
J 2
(-2073 2875);
DISPLAY 0.872340 (-2073 2875);
PAINT GREEN (-2073 2875);
DISPLAY INVISIBLE (-2073 2875);
FORCEADD TAP..1
R 2
(-2075 3825);
FORCEPROP 3 LASTPIN (-2025 3825) SIG_NAME M_F_CPU0_SB_CA<2>
J 0
(-2015 3835);
DISPLAY 0.659574 (-2015 3835);
PAINT MONO (-2015 3835);
DISPLAY INVISIBLE (-2015 3835);
FORCEPROP 1 LASTPIN (-2025 3825) BN 2
J 2
(-2013 3833);
DISPLAY 0.680851 (-2013 3833);
PAINT GREEN (-2013 3833);
FORCEPROP 2 LAST CDS_LIB standard
J 0
(-2075 3825);
DISPLAY INVISIBLE (-2075 3825);
FORCEPROP 1 LAST BODY_TYPE PLUMBING
J 2
(-2075 3875);
DISPLAY 0.872340 (-2075 3875);
PAINT GREEN (-2075 3875);
DISPLAY INVISIBLE (-2075 3875);
FORCEPROP 1 LAST HDL_TAP TRUE
J 2
(-2400 3700);
DISPLAY 0.872340 (-2400 3700);
DISPLAY INVISIBLE (-2400 3700);
FORCEPROP 1 LAST PATH I64
J 2
(-2073 3825);
DISPLAY 0.872340 (-2073 3825);
PAINT GREEN (-2073 3825);
DISPLAY INVISIBLE (-2073 3825);
FORCEADD TAP..1
R 2
(-2075 3775);
FORCEPROP 3 LASTPIN (-2025 3775) SIG_NAME M_F_CPU0_SB_CA<1>
J 0
(-2015 3785);
DISPLAY 0.659574 (-2015 3785);
PAINT MONO (-2015 3785);
DISPLAY INVISIBLE (-2015 3785);
FORCEPROP 1 LASTPIN (-2025 3775) BN 1
J 2
(-2013 3783);
DISPLAY 0.680851 (-2013 3783);
PAINT GREEN (-2013 3783);
FORCEPROP 2 LAST CDS_LIB standard
J 0
(-2075 3775);
DISPLAY INVISIBLE (-2075 3775);
FORCEPROP 1 LAST BODY_TYPE PLUMBING
J 2
(-2075 3825);
DISPLAY 0.872340 (-2075 3825);
PAINT GREEN (-2075 3825);
DISPLAY INVISIBLE (-2075 3825);
FORCEPROP 1 LAST HDL_TAP TRUE
J 2
(-2400 3650);
DISPLAY 0.872340 (-2400 3650);
DISPLAY INVISIBLE (-2400 3650);
FORCEPROP 1 LAST PATH I65
J 2
(-2073 3775);
DISPLAY 0.872340 (-2073 3775);
PAINT GREEN (-2073 3775);
DISPLAY INVISIBLE (-2073 3775);
FORCEADD TAP..1
R 2
(-2075 3725);
FORCEPROP 3 LASTPIN (-2025 3725) SIG_NAME M_F_CPU0_SB_CA<0>
J 0
(-2015 3735);
DISPLAY 0.659574 (-2015 3735);
PAINT MONO (-2015 3735);
DISPLAY INVISIBLE (-2015 3735);
FORCEPROP 1 LASTPIN (-2025 3725) BN 0
J 2
(-2013 3733);
DISPLAY 0.680851 (-2013 3733);
PAINT GREEN (-2013 3733);
FORCEPROP 2 LAST CDS_LIB standard
J 0
(-2075 3725);
DISPLAY INVISIBLE (-2075 3725);
FORCEPROP 1 LAST BODY_TYPE PLUMBING
J 2
(-2075 3775);
DISPLAY 0.872340 (-2075 3775);
PAINT GREEN (-2075 3775);
DISPLAY INVISIBLE (-2075 3775);
FORCEPROP 1 LAST HDL_TAP TRUE
J 2
(-2400 3600);
DISPLAY 0.872340 (-2400 3600);
DISPLAY INVISIBLE (-2400 3600);
FORCEPROP 1 LAST PATH I66
J 2
(-2073 3725);
DISPLAY 0.872340 (-2073 3725);
PAINT GREEN (-2073 3725);
DISPLAY INVISIBLE (-2073 3725);
FORCEADD TAP..1
R 2
(-2075 3875);
FORCEPROP 3 LASTPIN (-2025 3875) SIG_NAME M_F_CPU0_SB_CA<3>
J 0
(-2015 3885);
DISPLAY 0.659574 (-2015 3885);
PAINT MONO (-2015 3885);
DISPLAY INVISIBLE (-2015 3885);
FORCEPROP 1 LASTPIN (-2025 3875) BN 3
J 2
(-2013 3883);
DISPLAY 0.680851 (-2013 3883);
PAINT GREEN (-2013 3883);
FORCEPROP 2 LAST CDS_LIB standard
J 0
(-2075 3875);
DISPLAY INVISIBLE (-2075 3875);
FORCEPROP 1 LAST BODY_TYPE PLUMBING
J 2
(-2075 3925);
DISPLAY 0.872340 (-2075 3925);
PAINT GREEN (-2075 3925);
DISPLAY INVISIBLE (-2075 3925);
FORCEPROP 1 LAST HDL_TAP TRUE
J 2
(-2400 3750);
DISPLAY 0.872340 (-2400 3750);
DISPLAY INVISIBLE (-2400 3750);
FORCEPROP 1 LAST PATH I67
J 2
(-2073 3875);
DISPLAY 0.872340 (-2073 3875);
PAINT GREEN (-2073 3875);
DISPLAY INVISIBLE (-2073 3875);
FORCEADD TAP..1
R 2
(-2075 4025);
FORCEPROP 3 LASTPIN (-2025 4025) SIG_NAME M_F_CPU0_SB_CA<6>
J 0
(-2015 4035);
DISPLAY 0.659574 (-2015 4035);
PAINT MONO (-2015 4035);
DISPLAY INVISIBLE (-2015 4035);
FORCEPROP 1 LASTPIN (-2025 4025) BN 6
J 2
(-2013 4033);
DISPLAY 0.680851 (-2013 4033);
PAINT GREEN (-2013 4033);
FORCEPROP 2 LAST CDS_LIB standard
J 0
(-2075 4025);
DISPLAY INVISIBLE (-2075 4025);
FORCEPROP 1 LAST BODY_TYPE PLUMBING
J 2
(-2075 4075);
DISPLAY 0.872340 (-2075 4075);
PAINT GREEN (-2075 4075);
DISPLAY INVISIBLE (-2075 4075);
FORCEPROP 1 LAST HDL_TAP TRUE
J 2
(-2400 3900);
DISPLAY 0.872340 (-2400 3900);
DISPLAY INVISIBLE (-2400 3900);
FORCEPROP 1 LAST PATH I68
J 2
(-2073 4025);
DISPLAY 0.872340 (-2073 4025);
PAINT GREEN (-2073 4025);
DISPLAY INVISIBLE (-2073 4025);
FORCEADD TAP..1
R 2
(-2075 3975);
FORCEPROP 3 LASTPIN (-2025 3975) SIG_NAME M_F_CPU0_SB_CA<5>
J 0
(-2015 3985);
DISPLAY 0.659574 (-2015 3985);
PAINT MONO (-2015 3985);
DISPLAY INVISIBLE (-2015 3985);
FORCEPROP 1 LASTPIN (-2025 3975) BN 5
J 2
(-2013 3983);
DISPLAY 0.680851 (-2013 3983);
PAINT GREEN (-2013 3983);
FORCEPROP 2 LAST CDS_LIB standard
J 0
(-2075 3975);
DISPLAY INVISIBLE (-2075 3975);
FORCEPROP 1 LAST BODY_TYPE PLUMBING
J 2
(-2075 4025);
DISPLAY 0.872340 (-2075 4025);
PAINT GREEN (-2075 4025);
DISPLAY INVISIBLE (-2075 4025);
FORCEPROP 1 LAST HDL_TAP TRUE
J 2
(-2400 3850);
DISPLAY 0.872340 (-2400 3850);
DISPLAY INVISIBLE (-2400 3850);
FORCEPROP 1 LAST PATH I69
J 2
(-2073 3975);
DISPLAY 0.872340 (-2073 3975);
PAINT GREEN (-2073 3975);
DISPLAY INVISIBLE (-2073 3975);
FORCEADD TAP..1
R 2
(-2075 3925);
FORCEPROP 3 LASTPIN (-2025 3925) SIG_NAME M_F_CPU0_SB_CA<4>
J 0
(-2015 3935);
DISPLAY 0.659574 (-2015 3935);
PAINT MONO (-2015 3935);
DISPLAY INVISIBLE (-2015 3935);
FORCEPROP 1 LASTPIN (-2025 3925) BN 4
J 2
(-2013 3933);
DISPLAY 0.680851 (-2013 3933);
PAINT GREEN (-2013 3933);
FORCEPROP 2 LAST CDS_LIB standard
J 0
(-2075 3925);
DISPLAY INVISIBLE (-2075 3925);
FORCEPROP 1 LAST BODY_TYPE PLUMBING
J 2
(-2075 3975);
DISPLAY 0.872340 (-2075 3975);
PAINT GREEN (-2075 3975);
DISPLAY INVISIBLE (-2075 3975);
FORCEPROP 1 LAST HDL_TAP TRUE
J 2
(-2400 3800);
DISPLAY 0.872340 (-2400 3800);
DISPLAY INVISIBLE (-2400 3800);
FORCEPROP 1 LAST PATH I70
J 2
(-2073 3925);
DISPLAY 0.872340 (-2073 3925);
PAINT GREEN (-2073 3925);
DISPLAY INVISIBLE (-2073 3925);
FORCEADD TAP..1
R 2
(-2075 4125);
FORCEPROP 3 LASTPIN (-2025 4125) SIG_NAME M_F_CPU0_SA_CA<0>
J 0
(-2015 4135);
DISPLAY 0.659574 (-2015 4135);
PAINT MONO (-2015 4135);
DISPLAY INVISIBLE (-2015 4135);
FORCEPROP 1 LASTPIN (-2025 4125) BN 0
J 2
(-2013 4133);
DISPLAY 0.680851 (-2013 4133);
PAINT GREEN (-2013 4133);
FORCEPROP 2 LAST CDS_LIB standard
J 0
(-2075 4125);
DISPLAY INVISIBLE (-2075 4125);
FORCEPROP 1 LAST BODY_TYPE PLUMBING
J 2
(-2075 4175);
DISPLAY 0.872340 (-2075 4175);
PAINT GREEN (-2075 4175);
DISPLAY INVISIBLE (-2075 4175);
FORCEPROP 1 LAST HDL_TAP TRUE
J 2
(-2400 4000);
DISPLAY 0.872340 (-2400 4000);
DISPLAY INVISIBLE (-2400 4000);
FORCEPROP 1 LAST PATH I71
J 2
(-2073 4125);
DISPLAY 0.872340 (-2073 4125);
PAINT GREEN (-2073 4125);
DISPLAY INVISIBLE (-2073 4125);
FORCEADD TAP..1
R 2
(-2075 4175);
FORCEPROP 3 LASTPIN (-2025 4175) SIG_NAME M_F_CPU0_SA_CA<1>
J 0
(-2015 4185);
DISPLAY 0.659574 (-2015 4185);
PAINT MONO (-2015 4185);
DISPLAY INVISIBLE (-2015 4185);
FORCEPROP 1 LASTPIN (-2025 4175) BN 1
J 2
(-2013 4183);
DISPLAY 0.680851 (-2013 4183);
PAINT GREEN (-2013 4183);
FORCEPROP 2 LAST CDS_LIB standard
J 0
(-2075 4175);
DISPLAY INVISIBLE (-2075 4175);
FORCEPROP 1 LAST BODY_TYPE PLUMBING
J 2
(-2075 4225);
DISPLAY 0.872340 (-2075 4225);
PAINT GREEN (-2075 4225);
DISPLAY INVISIBLE (-2075 4225);
FORCEPROP 1 LAST HDL_TAP TRUE
J 2
(-2400 4050);
DISPLAY 0.872340 (-2400 4050);
DISPLAY INVISIBLE (-2400 4050);
FORCEPROP 1 LAST PATH I72
J 2
(-2073 4175);
DISPLAY 0.872340 (-2073 4175);
PAINT GREEN (-2073 4175);
DISPLAY INVISIBLE (-2073 4175);
FORCEADD TAP..1
R 2
(-2075 4225);
FORCEPROP 3 LASTPIN (-2025 4225) SIG_NAME M_F_CPU0_SA_CA<2>
J 0
(-2015 4235);
DISPLAY 0.659574 (-2015 4235);
PAINT MONO (-2015 4235);
DISPLAY INVISIBLE (-2015 4235);
FORCEPROP 1 LASTPIN (-2025 4225) BN 2
J 2
(-2013 4233);
DISPLAY 0.680851 (-2013 4233);
PAINT GREEN (-2013 4233);
FORCEPROP 2 LAST CDS_LIB standard
J 0
(-2075 4225);
DISPLAY INVISIBLE (-2075 4225);
FORCEPROP 1 LAST BODY_TYPE PLUMBING
J 2
(-2075 4275);
DISPLAY 0.872340 (-2075 4275);
PAINT GREEN (-2075 4275);
DISPLAY INVISIBLE (-2075 4275);
FORCEPROP 1 LAST HDL_TAP TRUE
J 2
(-2400 4100);
DISPLAY 0.872340 (-2400 4100);
DISPLAY INVISIBLE (-2400 4100);
FORCEPROP 1 LAST PATH I73
J 2
(-2073 4225);
DISPLAY 0.872340 (-2073 4225);
PAINT GREEN (-2073 4225);
DISPLAY INVISIBLE (-2073 4225);
FORCEADD TAP..1
R 2
(-2075 4325);
FORCEPROP 3 LASTPIN (-2025 4325) SIG_NAME M_F_CPU0_SA_CA<4>
J 0
(-2015 4335);
DISPLAY 0.659574 (-2015 4335);
PAINT MONO (-2015 4335);
DISPLAY INVISIBLE (-2015 4335);
FORCEPROP 1 LASTPIN (-2025 4325) BN 4
J 2
(-2013 4333);
DISPLAY 0.680851 (-2013 4333);
PAINT GREEN (-2013 4333);
FORCEPROP 2 LAST CDS_LIB standard
J 0
(-2075 4325);
DISPLAY INVISIBLE (-2075 4325);
FORCEPROP 1 LAST BODY_TYPE PLUMBING
J 2
(-2075 4375);
DISPLAY 0.872340 (-2075 4375);
PAINT GREEN (-2075 4375);
DISPLAY INVISIBLE (-2075 4375);
FORCEPROP 1 LAST HDL_TAP TRUE
J 2
(-2400 4200);
DISPLAY 0.872340 (-2400 4200);
DISPLAY INVISIBLE (-2400 4200);
FORCEPROP 1 LAST PATH I74
J 2
(-2073 4325);
DISPLAY 0.872340 (-2073 4325);
PAINT GREEN (-2073 4325);
DISPLAY INVISIBLE (-2073 4325);
FORCEADD TAP..1
R 2
(-2075 4275);
FORCEPROP 3 LASTPIN (-2025 4275) SIG_NAME M_F_CPU0_SA_CA<3>
J 0
(-2015 4285);
DISPLAY 0.659574 (-2015 4285);
PAINT MONO (-2015 4285);
DISPLAY INVISIBLE (-2015 4285);
FORCEPROP 1 LASTPIN (-2025 4275) BN 3
J 2
(-2013 4283);
DISPLAY 0.680851 (-2013 4283);
PAINT GREEN (-2013 4283);
FORCEPROP 2 LAST CDS_LIB standard
J 0
(-2075 4275);
DISPLAY INVISIBLE (-2075 4275);
FORCEPROP 1 LAST BODY_TYPE PLUMBING
J 2
(-2075 4325);
DISPLAY 0.872340 (-2075 4325);
PAINT GREEN (-2075 4325);
DISPLAY INVISIBLE (-2075 4325);
FORCEPROP 1 LAST HDL_TAP TRUE
J 2
(-2400 4150);
DISPLAY 0.872340 (-2400 4150);
DISPLAY INVISIBLE (-2400 4150);
FORCEPROP 1 LAST PATH I75
J 2
(-2073 4275);
DISPLAY 0.872340 (-2073 4275);
PAINT GREEN (-2073 4275);
DISPLAY INVISIBLE (-2073 4275);
FORCEADD TAP..1
R 2
(-2075 4375);
FORCEPROP 3 LASTPIN (-2025 4375) SIG_NAME M_F_CPU0_SA_CA<5>
J 0
(-2015 4385);
DISPLAY 0.659574 (-2015 4385);
PAINT MONO (-2015 4385);
DISPLAY INVISIBLE (-2015 4385);
FORCEPROP 1 LASTPIN (-2025 4375) BN 5
J 2
(-2013 4383);
DISPLAY 0.680851 (-2013 4383);
PAINT GREEN (-2013 4383);
FORCEPROP 2 LAST CDS_LIB standard
J 0
(-2075 4375);
DISPLAY INVISIBLE (-2075 4375);
FORCEPROP 1 LAST BODY_TYPE PLUMBING
J 2
(-2075 4425);
DISPLAY 0.872340 (-2075 4425);
PAINT GREEN (-2075 4425);
DISPLAY INVISIBLE (-2075 4425);
FORCEPROP 1 LAST HDL_TAP TRUE
J 2
(-2400 4250);
DISPLAY 0.872340 (-2400 4250);
DISPLAY INVISIBLE (-2400 4250);
FORCEPROP 1 LAST PATH I76
J 2
(-2073 4375);
DISPLAY 0.872340 (-2073 4375);
PAINT GREEN (-2073 4375);
DISPLAY INVISIBLE (-2073 4375);
FORCEADD TAP..1
(-425 2375);
FORCEPROP 3 LASTPIN (-475 2375) SIG_NAME M_F_CPU0_SB_DQ<23>
J 0
(-465 2385);
DISPLAY 0.659574 (-465 2385);
PAINT MONO (-465 2385);
DISPLAY INVISIBLE (-465 2385);
FORCEPROP 1 LASTPIN (-475 2375) BN 23
J 0
(-487 2383);
DISPLAY 0.680851 (-487 2383);
PAINT GREEN (-487 2383);
FORCEPROP 2 LAST CDS_LIB standard
J 0
(-425 2375);
DISPLAY INVISIBLE (-425 2375);
FORCEPROP 1 LAST BODY_TYPE PLUMBING
J 0
(-425 2425);
DISPLAY 0.872340 (-425 2425);
PAINT GREEN (-425 2425);
DISPLAY INVISIBLE (-425 2425);
FORCEPROP 1 LAST HDL_TAP TRUE
J 0
(-100 2250);
DISPLAY 0.872340 (-100 2250);
DISPLAY INVISIBLE (-100 2250);
FORCEPROP 1 LAST PATH I77
J 0
(-427 2375);
DISPLAY 0.872340 (-427 2375);
PAINT GREEN (-427 2375);
DISPLAY INVISIBLE (-427 2375);
FORCEADD TAP..1
(-425 2575);
FORCEPROP 3 LASTPIN (-475 2575) SIG_NAME M_F_CPU0_SB_DQ<27>
J 0
(-465 2585);
DISPLAY 0.659574 (-465 2585);
PAINT MONO (-465 2585);
DISPLAY INVISIBLE (-465 2585);
FORCEPROP 1 LASTPIN (-475 2575) BN 27
J 0
(-487 2583);
DISPLAY 0.680851 (-487 2583);
PAINT GREEN (-487 2583);
FORCEPROP 2 LAST CDS_LIB standard
J 0
(-425 2575);
DISPLAY INVISIBLE (-425 2575);
FORCEPROP 1 LAST BODY_TYPE PLUMBING
J 0
(-425 2625);
DISPLAY 0.872340 (-425 2625);
PAINT GREEN (-425 2625);
DISPLAY INVISIBLE (-425 2625);
FORCEPROP 1 LAST HDL_TAP TRUE
J 0
(-100 2450);
DISPLAY 0.872340 (-100 2450);
DISPLAY INVISIBLE (-100 2450);
FORCEPROP 1 LAST PATH I78
J 0
(-427 2575);
DISPLAY 0.872340 (-427 2575);
PAINT GREEN (-427 2575);
DISPLAY INVISIBLE (-427 2575);
FORCEADD TAP..1
(-425 2475);
FORCEPROP 3 LASTPIN (-475 2475) SIG_NAME M_F_CPU0_SB_DQ<25>
J 0
(-465 2485);
DISPLAY 0.659574 (-465 2485);
PAINT MONO (-465 2485);
DISPLAY INVISIBLE (-465 2485);
FORCEPROP 1 LASTPIN (-475 2475) BN 25
J 0
(-487 2483);
DISPLAY 0.680851 (-487 2483);
PAINT GREEN (-487 2483);
FORCEPROP 2 LAST CDS_LIB standard
J 0
(-425 2475);
DISPLAY INVISIBLE (-425 2475);
FORCEPROP 1 LAST BODY_TYPE PLUMBING
J 0
(-425 2525);
DISPLAY 0.872340 (-425 2525);
PAINT GREEN (-425 2525);
DISPLAY INVISIBLE (-425 2525);
FORCEPROP 1 LAST HDL_TAP TRUE
J 0
(-100 2350);
DISPLAY 0.872340 (-100 2350);
DISPLAY INVISIBLE (-100 2350);
FORCEPROP 1 LAST PATH I79
J 0
(-427 2475);
DISPLAY 0.872340 (-427 2475);
PAINT GREEN (-427 2475);
DISPLAY INVISIBLE (-427 2475);
FORCEADD OFFPAGE..1
(-2925 1925);
FORCEPROP 2 LAST $XR0 93 
J 0
(-3176 1925);
DISPLAY 0.638298 (-3176 1925);
PAINT MONO (-3176 1925);
FORCEPROP 2 LAST CDS_LIB standard
J 0
(-2925 1925);
PAINT MONO (-2925 1925);
DISPLAY INVISIBLE (-2925 1925);
FORCEPROP 1 LAST OFFPAGE TRUE
J 0
(-2600 1800);
DISPLAY 0.872340 (-2600 1800);
DISPLAY INVISIBLE (-2600 1800);
FORCEPROP 1 LAST COMMENT_BODY TRUE
J 0
(-2800 1825);
DISPLAY 0.872340 (-2800 1825);
PAINT GREEN (-2800 1825);
DISPLAY INVISIBLE (-2800 1825);
FORCEPROP 2 LAST PATH I8
J 0
(-2875 2000);
DISPLAY 1.021277 (-2875 2000);
DISPLAY INVISIBLE (-2875 2000);
FORCEADD TAP..1
(-425 2525);
FORCEPROP 3 LASTPIN (-475 2525) SIG_NAME M_F_CPU0_SB_DQ<26>
J 0
(-465 2535);
DISPLAY 0.659574 (-465 2535);
PAINT MONO (-465 2535);
DISPLAY INVISIBLE (-465 2535);
FORCEPROP 1 LASTPIN (-475 2525) BN 26
J 0
(-487 2533);
DISPLAY 0.680851 (-487 2533);
PAINT GREEN (-487 2533);
FORCEPROP 2 LAST CDS_LIB standard
J 0
(-425 2525);
DISPLAY INVISIBLE (-425 2525);
FORCEPROP 1 LAST BODY_TYPE PLUMBING
J 0
(-425 2575);
DISPLAY 0.872340 (-425 2575);
PAINT GREEN (-425 2575);
DISPLAY INVISIBLE (-425 2575);
FORCEPROP 1 LAST HDL_TAP TRUE
J 0
(-100 2400);
DISPLAY 0.872340 (-100 2400);
DISPLAY INVISIBLE (-100 2400);
FORCEPROP 1 LAST PATH I80
J 0
(-427 2525);
DISPLAY 0.872340 (-427 2525);
PAINT GREEN (-427 2525);
DISPLAY INVISIBLE (-427 2525);
FORCEADD TAP..1
(-425 2425);
FORCEPROP 3 LASTPIN (-475 2425) SIG_NAME M_F_CPU0_SB_DQ<24>
J 0
(-465 2435);
DISPLAY 0.659574 (-465 2435);
PAINT MONO (-465 2435);
DISPLAY INVISIBLE (-465 2435);
FORCEPROP 1 LASTPIN (-475 2425) BN 24
J 0
(-487 2433);
DISPLAY 0.680851 (-487 2433);
PAINT GREEN (-487 2433);
FORCEPROP 2 LAST CDS_LIB standard
J 0
(-425 2425);
DISPLAY INVISIBLE (-425 2425);
FORCEPROP 1 LAST BODY_TYPE PLUMBING
J 0
(-425 2475);
DISPLAY 0.872340 (-425 2475);
PAINT GREEN (-425 2475);
DISPLAY INVISIBLE (-425 2475);
FORCEPROP 1 LAST HDL_TAP TRUE
J 0
(-100 2300);
DISPLAY 0.872340 (-100 2300);
DISPLAY INVISIBLE (-100 2300);
FORCEPROP 1 LAST PATH I81
J 0
(-427 2425);
DISPLAY 0.872340 (-427 2425);
PAINT GREEN (-427 2425);
DISPLAY INVISIBLE (-427 2425);
FORCEADD TAP..1
(-425 2775);
FORCEPROP 3 LASTPIN (-475 2775) SIG_NAME M_F_CPU0_SB_DQ<31>
J 0
(-465 2785);
DISPLAY 0.659574 (-465 2785);
PAINT MONO (-465 2785);
DISPLAY INVISIBLE (-465 2785);
FORCEPROP 1 LASTPIN (-475 2775) BN 31
J 0
(-487 2783);
DISPLAY 0.680851 (-487 2783);
PAINT GREEN (-487 2783);
FORCEPROP 2 LAST CDS_LIB standard
J 0
(-425 2775);
DISPLAY INVISIBLE (-425 2775);
FORCEPROP 1 LAST BODY_TYPE PLUMBING
J 0
(-425 2825);
DISPLAY 0.872340 (-425 2825);
PAINT GREEN (-425 2825);
DISPLAY INVISIBLE (-425 2825);
FORCEPROP 1 LAST HDL_TAP TRUE
J 0
(-100 2650);
DISPLAY 0.872340 (-100 2650);
DISPLAY INVISIBLE (-100 2650);
FORCEPROP 1 LAST PATH I82
J 0
(-427 2775);
DISPLAY 0.872340 (-427 2775);
PAINT GREEN (-427 2775);
DISPLAY INVISIBLE (-427 2775);
FORCEADD TAP..1
(-425 2725);
FORCEPROP 3 LASTPIN (-475 2725) SIG_NAME M_F_CPU0_SB_DQ<30>
J 0
(-465 2735);
DISPLAY 0.659574 (-465 2735);
PAINT MONO (-465 2735);
DISPLAY INVISIBLE (-465 2735);
FORCEPROP 1 LASTPIN (-475 2725) BN 30
J 0
(-487 2733);
DISPLAY 0.680851 (-487 2733);
PAINT GREEN (-487 2733);
FORCEPROP 2 LAST CDS_LIB standard
J 0
(-425 2725);
DISPLAY INVISIBLE (-425 2725);
FORCEPROP 1 LAST BODY_TYPE PLUMBING
J 0
(-425 2775);
DISPLAY 0.872340 (-425 2775);
PAINT GREEN (-425 2775);
DISPLAY INVISIBLE (-425 2775);
FORCEPROP 1 LAST HDL_TAP TRUE
J 0
(-100 2600);
DISPLAY 0.872340 (-100 2600);
DISPLAY INVISIBLE (-100 2600);
FORCEPROP 1 LAST PATH I83
J 0
(-427 2725);
DISPLAY 0.872340 (-427 2725);
PAINT GREEN (-427 2725);
DISPLAY INVISIBLE (-427 2725);
FORCEADD TAP..1
(-425 2675);
FORCEPROP 3 LASTPIN (-475 2675) SIG_NAME M_F_CPU0_SB_DQ<29>
J 0
(-465 2685);
DISPLAY 0.659574 (-465 2685);
PAINT MONO (-465 2685);
DISPLAY INVISIBLE (-465 2685);
FORCEPROP 1 LASTPIN (-475 2675) BN 29
J 0
(-487 2683);
DISPLAY 0.680851 (-487 2683);
PAINT GREEN (-487 2683);
FORCEPROP 2 LAST CDS_LIB standard
J 0
(-425 2675);
DISPLAY INVISIBLE (-425 2675);
FORCEPROP 1 LAST BODY_TYPE PLUMBING
J 0
(-425 2725);
DISPLAY 0.872340 (-425 2725);
PAINT GREEN (-425 2725);
DISPLAY INVISIBLE (-425 2725);
FORCEPROP 1 LAST HDL_TAP TRUE
J 0
(-100 2550);
DISPLAY 0.872340 (-100 2550);
DISPLAY INVISIBLE (-100 2550);
FORCEPROP 1 LAST PATH I84
J 0
(-427 2675);
DISPLAY 0.872340 (-427 2675);
PAINT GREEN (-427 2675);
DISPLAY INVISIBLE (-427 2675);
FORCEADD TAP..1
(-425 2625);
FORCEPROP 3 LASTPIN (-475 2625) SIG_NAME M_F_CPU0_SB_DQ<28>
J 0
(-465 2635);
DISPLAY 0.659574 (-465 2635);
PAINT MONO (-465 2635);
DISPLAY INVISIBLE (-465 2635);
FORCEPROP 1 LASTPIN (-475 2625) BN 28
J 0
(-487 2633);
DISPLAY 0.680851 (-487 2633);
PAINT GREEN (-487 2633);
FORCEPROP 2 LAST CDS_LIB standard
J 0
(-425 2625);
DISPLAY INVISIBLE (-425 2625);
FORCEPROP 1 LAST BODY_TYPE PLUMBING
J 0
(-425 2675);
DISPLAY 0.872340 (-425 2675);
PAINT GREEN (-425 2675);
DISPLAY INVISIBLE (-425 2675);
FORCEPROP 1 LAST HDL_TAP TRUE
J 0
(-100 2500);
DISPLAY 0.872340 (-100 2500);
DISPLAY INVISIBLE (-100 2500);
FORCEPROP 1 LAST PATH I85
J 0
(-427 2625);
DISPLAY 0.872340 (-427 2625);
PAINT GREEN (-427 2625);
DISPLAY INVISIBLE (-427 2625);
FORCEADD TAP..1
(-425 2875);
FORCEPROP 3 LASTPIN (-475 2875) SIG_NAME M_F_CPU0_SA_DQ<0>
J 0
(-465 2885);
DISPLAY 0.659574 (-465 2885);
PAINT MONO (-465 2885);
DISPLAY INVISIBLE (-465 2885);
FORCEPROP 1 LASTPIN (-475 2875) BN 0
J 0
(-487 2883);
DISPLAY 0.680851 (-487 2883);
PAINT GREEN (-487 2883);
FORCEPROP 2 LAST CDS_LIB standard
J 0
(-425 2875);
PAINT MONO (-425 2875);
DISPLAY INVISIBLE (-425 2875);
FORCEPROP 1 LAST BODY_TYPE PLUMBING
J 0
(-425 2925);
DISPLAY 0.872340 (-425 2925);
PAINT GREEN (-425 2925);
DISPLAY INVISIBLE (-425 2925);
FORCEPROP 1 LAST HDL_TAP TRUE
J 0
(-100 2750);
DISPLAY 0.872340 (-100 2750);
DISPLAY INVISIBLE (-100 2750);
FORCEPROP 1 LAST PATH I86
J 0
(-427 2875);
DISPLAY 0.872340 (-427 2875);
PAINT GREEN (-427 2875);
DISPLAY INVISIBLE (-427 2875);
FORCEADD TAP..1
(-425 2975);
FORCEPROP 3 LASTPIN (-475 2975) SIG_NAME M_F_CPU0_SA_DQ<2>
J 0
(-465 2985);
DISPLAY 0.659574 (-465 2985);
PAINT MONO (-465 2985);
DISPLAY INVISIBLE (-465 2985);
FORCEPROP 1 LASTPIN (-475 2975) BN 2
J 0
(-487 2983);
DISPLAY 0.680851 (-487 2983);
PAINT GREEN (-487 2983);
FORCEPROP 2 LAST CDS_LIB standard
J 0
(-425 2975);
PAINT MONO (-425 2975);
DISPLAY INVISIBLE (-425 2975);
FORCEPROP 1 LAST BODY_TYPE PLUMBING
J 0
(-425 3025);
DISPLAY 0.872340 (-425 3025);
PAINT GREEN (-425 3025);
DISPLAY INVISIBLE (-425 3025);
FORCEPROP 1 LAST HDL_TAP TRUE
J 0
(-100 2850);
DISPLAY 0.872340 (-100 2850);
DISPLAY INVISIBLE (-100 2850);
FORCEPROP 1 LAST PATH I87
J 0
(-427 2975);
DISPLAY 0.872340 (-427 2975);
PAINT GREEN (-427 2975);
DISPLAY INVISIBLE (-427 2975);
FORCEADD TAP..1
(-425 2925);
FORCEPROP 3 LASTPIN (-475 2925) SIG_NAME M_F_CPU0_SA_DQ<1>
J 0
(-465 2935);
DISPLAY 0.659574 (-465 2935);
PAINT MONO (-465 2935);
DISPLAY INVISIBLE (-465 2935);
FORCEPROP 1 LASTPIN (-475 2925) BN 1
J 0
(-487 2933);
DISPLAY 0.680851 (-487 2933);
PAINT GREEN (-487 2933);
FORCEPROP 2 LAST CDS_LIB standard
J 0
(-425 2925);
PAINT MONO (-425 2925);
DISPLAY INVISIBLE (-425 2925);
FORCEPROP 1 LAST BODY_TYPE PLUMBING
J 0
(-425 2975);
DISPLAY 0.872340 (-425 2975);
PAINT GREEN (-425 2975);
DISPLAY INVISIBLE (-425 2975);
FORCEPROP 1 LAST HDL_TAP TRUE
J 0
(-100 2800);
DISPLAY 0.872340 (-100 2800);
DISPLAY INVISIBLE (-100 2800);
FORCEPROP 1 LAST PATH I88
J 0
(-427 2925);
DISPLAY 0.872340 (-427 2925);
PAINT GREEN (-427 2925);
DISPLAY INVISIBLE (-427 2925);
FORCEADD TAP..1
(-425 3075);
FORCEPROP 3 LASTPIN (-475 3075) SIG_NAME M_F_CPU0_SA_DQ<4>
J 0
(-465 3085);
DISPLAY 0.659574 (-465 3085);
PAINT MONO (-465 3085);
DISPLAY INVISIBLE (-465 3085);
FORCEPROP 1 LASTPIN (-475 3075) BN 4
J 0
(-487 3083);
DISPLAY 0.680851 (-487 3083);
PAINT GREEN (-487 3083);
FORCEPROP 2 LAST CDS_LIB standard
J 0
(-425 3075);
PAINT MONO (-425 3075);
DISPLAY INVISIBLE (-425 3075);
FORCEPROP 1 LAST BODY_TYPE PLUMBING
J 0
(-425 3125);
DISPLAY 0.872340 (-425 3125);
PAINT GREEN (-425 3125);
DISPLAY INVISIBLE (-425 3125);
FORCEPROP 1 LAST HDL_TAP TRUE
J 0
(-100 2950);
DISPLAY 0.872340 (-100 2950);
DISPLAY INVISIBLE (-100 2950);
FORCEPROP 1 LAST PATH I89
J 0
(-427 3075);
DISPLAY 0.872340 (-427 3075);
PAINT GREEN (-427 3075);
DISPLAY INVISIBLE (-427 3075);
FORCEADD OFFPAGE..1
(-2925 1875);
FORCEPROP 2 LAST $XR7 97 
J 0
(-3447 1839);
DISPLAY 0.638298 (-3447 1839);
PAINT MONO (-3447 1839);
FORCEPROP 2 LAST $XR6 96 
J 0
(-3357 1839);
DISPLAY 0.638298 (-3357 1839);
PAINT MONO (-3357 1839);
FORCEPROP 2 LAST $XR5 95 
J 0
(-3267 1839);
DISPLAY 0.638298 (-3267 1839);
PAINT MONO (-3267 1839);
FORCEPROP 2 LAST $XR4 94 
J 0
(-3177 1839);
DISPLAY 0.638298 (-3177 1839);
PAINT MONO (-3177 1839);
FORCEPROP 2 LAST $XR3 92 
J 0
(-3447 1875);
DISPLAY 0.638298 (-3447 1875);
PAINT MONO (-3447 1875);
FORCEPROP 2 LAST $XR2 91 
J 0
(-3357 1875);
DISPLAY 0.638298 (-3357 1875);
PAINT MONO (-3357 1875);
FORCEPROP 2 LAST $XR1 90 
J 0
(-3267 1875);
DISPLAY 0.638298 (-3267 1875);
PAINT MONO (-3267 1875);
FORCEPROP 2 LAST $XR0 229 
J 0
(-3177 1875);
DISPLAY 0.638298 (-3177 1875);
PAINT MONO (-3177 1875);
FORCEPROP 2 LAST CDS_LIB standard
J 0
(-2925 1875);
PAINT MONO (-2925 1875);
DISPLAY INVISIBLE (-2925 1875);
FORCEPROP 1 LAST OFFPAGE TRUE
J 0
(-2600 1750);
DISPLAY 0.872340 (-2600 1750);
DISPLAY INVISIBLE (-2600 1750);
FORCEPROP 1 LAST COMMENT_BODY TRUE
J 0
(-2800 1775);
DISPLAY 0.872340 (-2800 1775);
PAINT GREEN (-2800 1775);
DISPLAY INVISIBLE (-2800 1775);
FORCEPROP 2 LAST PATH I9
J 0
(-2875 1950);
DISPLAY 1.021277 (-2875 1950);
DISPLAY INVISIBLE (-2875 1950);
FORCEADD TAP..1
(-425 3025);
FORCEPROP 3 LASTPIN (-475 3025) SIG_NAME M_F_CPU0_SA_DQ<3>
J 0
(-465 3035);
DISPLAY 0.659574 (-465 3035);
PAINT MONO (-465 3035);
DISPLAY INVISIBLE (-465 3035);
FORCEPROP 1 LASTPIN (-475 3025) BN 3
J 0
(-487 3033);
DISPLAY 0.680851 (-487 3033);
PAINT GREEN (-487 3033);
FORCEPROP 2 LAST CDS_LIB standard
J 0
(-425 3025);
PAINT MONO (-425 3025);
DISPLAY INVISIBLE (-425 3025);
FORCEPROP 1 LAST BODY_TYPE PLUMBING
J 0
(-425 3075);
DISPLAY 0.872340 (-425 3075);
PAINT GREEN (-425 3075);
DISPLAY INVISIBLE (-425 3075);
FORCEPROP 1 LAST HDL_TAP TRUE
J 0
(-100 2900);
DISPLAY 0.872340 (-100 2900);
DISPLAY INVISIBLE (-100 2900);
FORCEPROP 1 LAST PATH I90
J 0
(-427 3025);
DISPLAY 0.872340 (-427 3025);
PAINT GREEN (-427 3025);
DISPLAY INVISIBLE (-427 3025);
FORCEADD TAP..1
(-425 3325);
FORCEPROP 3 LASTPIN (-475 3325) SIG_NAME M_F_CPU0_SA_DQ<9>
J 0
(-465 3335);
DISPLAY 0.659574 (-465 3335);
PAINT MONO (-465 3335);
DISPLAY INVISIBLE (-465 3335);
FORCEPROP 1 LASTPIN (-475 3325) BN 9
J 0
(-487 3333);
DISPLAY 0.680851 (-487 3333);
PAINT GREEN (-487 3333);
FORCEPROP 2 LAST CDS_LIB standard
J 0
(-425 3325);
PAINT MONO (-425 3325);
DISPLAY INVISIBLE (-425 3325);
FORCEPROP 1 LAST BODY_TYPE PLUMBING
J 0
(-425 3375);
DISPLAY 0.872340 (-425 3375);
PAINT GREEN (-425 3375);
DISPLAY INVISIBLE (-425 3375);
FORCEPROP 1 LAST HDL_TAP TRUE
J 0
(-100 3200);
DISPLAY 0.872340 (-100 3200);
DISPLAY INVISIBLE (-100 3200);
FORCEPROP 1 LAST PATH I91
J 0
(-427 3325);
DISPLAY 0.872340 (-427 3325);
PAINT GREEN (-427 3325);
DISPLAY INVISIBLE (-427 3325);
FORCEADD TAP..1
(-425 3175);
FORCEPROP 3 LASTPIN (-475 3175) SIG_NAME M_F_CPU0_SA_DQ<6>
J 0
(-465 3185);
DISPLAY 0.659574 (-465 3185);
PAINT MONO (-465 3185);
DISPLAY INVISIBLE (-465 3185);
FORCEPROP 1 LASTPIN (-475 3175) BN 6
J 0
(-487 3183);
DISPLAY 0.680851 (-487 3183);
PAINT GREEN (-487 3183);
FORCEPROP 2 LAST CDS_LIB standard
J 0
(-425 3175);
PAINT MONO (-425 3175);
DISPLAY INVISIBLE (-425 3175);
FORCEPROP 1 LAST BODY_TYPE PLUMBING
J 0
(-425 3225);
DISPLAY 0.872340 (-425 3225);
PAINT GREEN (-425 3225);
DISPLAY INVISIBLE (-425 3225);
FORCEPROP 1 LAST HDL_TAP TRUE
J 0
(-100 3050);
DISPLAY 0.872340 (-100 3050);
DISPLAY INVISIBLE (-100 3050);
FORCEPROP 1 LAST PATH I92
J 0
(-427 3175);
DISPLAY 0.872340 (-427 3175);
PAINT GREEN (-427 3175);
DISPLAY INVISIBLE (-427 3175);
FORCEADD TAP..1
(-425 3275);
FORCEPROP 3 LASTPIN (-475 3275) SIG_NAME M_F_CPU0_SA_DQ<8>
J 0
(-465 3285);
DISPLAY 0.659574 (-465 3285);
PAINT MONO (-465 3285);
DISPLAY INVISIBLE (-465 3285);
FORCEPROP 1 LASTPIN (-475 3275) BN 8
J 0
(-487 3283);
DISPLAY 0.680851 (-487 3283);
PAINT GREEN (-487 3283);
FORCEPROP 2 LAST CDS_LIB standard
J 0
(-425 3275);
PAINT MONO (-425 3275);
DISPLAY INVISIBLE (-425 3275);
FORCEPROP 1 LAST BODY_TYPE PLUMBING
J 0
(-425 3325);
DISPLAY 0.872340 (-425 3325);
PAINT GREEN (-425 3325);
DISPLAY INVISIBLE (-425 3325);
FORCEPROP 1 LAST HDL_TAP TRUE
J 0
(-100 3150);
DISPLAY 0.872340 (-100 3150);
DISPLAY INVISIBLE (-100 3150);
FORCEPROP 1 LAST PATH I93
J 0
(-427 3275);
DISPLAY 0.872340 (-427 3275);
PAINT GREEN (-427 3275);
DISPLAY INVISIBLE (-427 3275);
FORCEADD TAP..1
(-425 3225);
FORCEPROP 3 LASTPIN (-475 3225) SIG_NAME M_F_CPU0_SA_DQ<7>
J 0
(-465 3235);
DISPLAY 0.659574 (-465 3235);
PAINT MONO (-465 3235);
DISPLAY INVISIBLE (-465 3235);
FORCEPROP 1 LASTPIN (-475 3225) BN 7
J 0
(-487 3233);
DISPLAY 0.680851 (-487 3233);
PAINT GREEN (-487 3233);
FORCEPROP 2 LAST CDS_LIB standard
J 0
(-425 3225);
PAINT MONO (-425 3225);
DISPLAY INVISIBLE (-425 3225);
FORCEPROP 1 LAST BODY_TYPE PLUMBING
J 0
(-425 3275);
DISPLAY 0.872340 (-425 3275);
PAINT GREEN (-425 3275);
DISPLAY INVISIBLE (-425 3275);
FORCEPROP 1 LAST HDL_TAP TRUE
J 0
(-100 3100);
DISPLAY 0.872340 (-100 3100);
DISPLAY INVISIBLE (-100 3100);
FORCEPROP 1 LAST PATH I94
J 0
(-427 3225);
DISPLAY 0.872340 (-427 3225);
PAINT GREEN (-427 3225);
DISPLAY INVISIBLE (-427 3225);
FORCEADD TAP..1
(-425 3125);
FORCEPROP 3 LASTPIN (-475 3125) SIG_NAME M_F_CPU0_SA_DQ<5>
J 0
(-465 3135);
DISPLAY 0.659574 (-465 3135);
PAINT MONO (-465 3135);
DISPLAY INVISIBLE (-465 3135);
FORCEPROP 1 LASTPIN (-475 3125) BN 5
J 0
(-487 3133);
DISPLAY 0.680851 (-487 3133);
PAINT GREEN (-487 3133);
FORCEPROP 2 LAST CDS_LIB standard
J 0
(-425 3125);
PAINT MONO (-425 3125);
DISPLAY INVISIBLE (-425 3125);
FORCEPROP 1 LAST BODY_TYPE PLUMBING
J 0
(-425 3175);
DISPLAY 0.872340 (-425 3175);
PAINT GREEN (-425 3175);
DISPLAY INVISIBLE (-425 3175);
FORCEPROP 1 LAST HDL_TAP TRUE
J 0
(-100 3000);
DISPLAY 0.872340 (-100 3000);
DISPLAY INVISIBLE (-100 3000);
FORCEPROP 1 LAST PATH I95
J 0
(-427 3125);
DISPLAY 0.872340 (-427 3125);
PAINT GREEN (-427 3125);
DISPLAY INVISIBLE (-427 3125);
FORCEADD TAP..1
(-425 3375);
FORCEPROP 3 LASTPIN (-475 3375) SIG_NAME M_F_CPU0_SA_DQ<10>
J 0
(-465 3385);
DISPLAY 0.659574 (-465 3385);
PAINT MONO (-465 3385);
DISPLAY INVISIBLE (-465 3385);
FORCEPROP 1 LASTPIN (-475 3375) BN 10
J 0
(-487 3383);
DISPLAY 0.680851 (-487 3383);
PAINT GREEN (-487 3383);
FORCEPROP 2 LAST CDS_LIB standard
J 0
(-425 3375);
PAINT MONO (-425 3375);
DISPLAY INVISIBLE (-425 3375);
FORCEPROP 1 LAST BODY_TYPE PLUMBING
J 0
(-425 3425);
DISPLAY 0.872340 (-425 3425);
PAINT GREEN (-425 3425);
DISPLAY INVISIBLE (-425 3425);
FORCEPROP 1 LAST HDL_TAP TRUE
J 0
(-100 3250);
DISPLAY 0.872340 (-100 3250);
DISPLAY INVISIBLE (-100 3250);
FORCEPROP 1 LAST PATH I96
J 0
(-427 3375);
DISPLAY 0.872340 (-427 3375);
PAINT GREEN (-427 3375);
DISPLAY INVISIBLE (-427 3375);
FORCEADD TAP..1
(-425 3425);
FORCEPROP 3 LASTPIN (-475 3425) SIG_NAME M_F_CPU0_SA_DQ<11>
J 0
(-465 3435);
DISPLAY 0.659574 (-465 3435);
PAINT MONO (-465 3435);
DISPLAY INVISIBLE (-465 3435);
FORCEPROP 1 LASTPIN (-475 3425) BN 11
J 0
(-487 3433);
DISPLAY 0.680851 (-487 3433);
PAINT GREEN (-487 3433);
FORCEPROP 2 LAST CDS_LIB standard
J 0
(-425 3425);
PAINT MONO (-425 3425);
DISPLAY INVISIBLE (-425 3425);
FORCEPROP 1 LAST BODY_TYPE PLUMBING
J 0
(-425 3475);
DISPLAY 0.872340 (-425 3475);
PAINT GREEN (-425 3475);
DISPLAY INVISIBLE (-425 3475);
FORCEPROP 1 LAST HDL_TAP TRUE
J 0
(-100 3300);
DISPLAY 0.872340 (-100 3300);
DISPLAY INVISIBLE (-100 3300);
FORCEPROP 1 LAST PATH I97
J 0
(-427 3425);
DISPLAY 0.872340 (-427 3425);
PAINT GREEN (-427 3425);
DISPLAY INVISIBLE (-427 3425);
FORCEADD TAP..1
(-425 3475);
FORCEPROP 3 LASTPIN (-475 3475) SIG_NAME M_F_CPU0_SA_DQ<12>
J 0
(-465 3485);
DISPLAY 0.659574 (-465 3485);
PAINT MONO (-465 3485);
DISPLAY INVISIBLE (-465 3485);
FORCEPROP 1 LASTPIN (-475 3475) BN 12
J 0
(-487 3483);
DISPLAY 0.680851 (-487 3483);
PAINT GREEN (-487 3483);
FORCEPROP 2 LAST CDS_LIB standard
J 0
(-425 3475);
PAINT MONO (-425 3475);
DISPLAY INVISIBLE (-425 3475);
FORCEPROP 1 LAST BODY_TYPE PLUMBING
J 0
(-425 3525);
DISPLAY 0.872340 (-425 3525);
PAINT GREEN (-425 3525);
DISPLAY INVISIBLE (-425 3525);
FORCEPROP 1 LAST HDL_TAP TRUE
J 0
(-100 3350);
DISPLAY 0.872340 (-100 3350);
DISPLAY INVISIBLE (-100 3350);
FORCEPROP 1 LAST PATH I98
J 0
(-427 3475);
DISPLAY 0.872340 (-427 3475);
PAINT GREEN (-427 3475);
DISPLAY INVISIBLE (-427 3475);
FORCEADD TAP..1
(-425 3625);
FORCEPROP 3 LASTPIN (-475 3625) SIG_NAME M_F_CPU0_SA_DQ<15>
J 0
(-465 3635);
DISPLAY 0.659574 (-465 3635);
PAINT MONO (-465 3635);
DISPLAY INVISIBLE (-465 3635);
FORCEPROP 1 LASTPIN (-475 3625) BN 15
J 0
(-487 3633);
DISPLAY 0.680851 (-487 3633);
PAINT GREEN (-487 3633);
FORCEPROP 2 LAST CDS_LIB standard
J 0
(-425 3625);
PAINT MONO (-425 3625);
DISPLAY INVISIBLE (-425 3625);
FORCEPROP 1 LAST BODY_TYPE PLUMBING
J 0
(-425 3675);
DISPLAY 0.872340 (-425 3675);
PAINT GREEN (-425 3675);
DISPLAY INVISIBLE (-425 3675);
FORCEPROP 1 LAST HDL_TAP TRUE
J 0
(-100 3500);
DISPLAY 0.872340 (-100 3500);
DISPLAY INVISIBLE (-100 3500);
FORCEPROP 1 LAST PATH I99
J 0
(-427 3625);
DISPLAY 0.872340 (-427 3625);
PAINT GREEN (-427 3625);
DISPLAY INVISIBLE (-427 3625);
FORCEADD CAD_NOTE..1
(1425 -25);
FORCEPROP 0 LAST S1 PLACE THE BYPASS CAPS CLOSE TO DIMM
J 0
(1300 -150);
DISPLAY 1.021277 (1300 -150);
PAINT WHITE (1300 -150);
FORCEPROP 2 LAST CDS_LIB logical_power
J 0
(1425 -25);
PAINT MONO (1425 -25);
DISPLAY INVISIBLE (1425 -25);
FORCEPROP 1 LAST COMMENT_BODY TRUE
J 0
(1450 75);
DISPLAY 0.978723 (1450 75);
DISPLAY INVISIBLE (1450 75);
FORCEADD QUANTA_TITLE_BLOCK_C..1
(5875 -1350);
FORCEPROP 0 LAST CDS_CON_LAST_MODIFIED Fri Aug 25 14:01:12 2023
J 0
(3990 -1335);
PAINT MONO (3990 -1335);
DISPLAY INVISIBLE (3990 -1335);
FORCEPROP 1 LAST CUSTOM_TXT_CDS <CON_LAST_MODIFIED>
J 0
(3990 -1335);
DISPLAY 0.978723 (3990 -1335);
FORCEPROP 2 LAST CUSTOM_TXT_CDS <XR_PAGE_TITLE>
J 0
(-2015 3900);
DISPLAY 0.638298 (-2015 3900);
PAINT PINK (-2015 3900);
DISPLAY INVISIBLE (-2015 3900);
FORCEPROP 2 LAST CUSTOM_TXT_CDS <Q_NUMBER>
J 0
(4472 -1247);
DISPLAY 1.212766 (4472 -1247);
FORCEPROP 1 LAST CUSTOM_TXT_CDS <NAME_2>
J 0
(2700 -1300);
FORCEPROP 1 LAST CUSTOM_TXT_CDS <NAME_1>
J 0
(2700 -1175);
FORCEPROP 1 LAST CUSTOM_TXT_CDS <Q_PROJ>
J 0
(3493 -1248);
DISPLAY 1.212766 (3493 -1248);
FORCEPROP 1 LAST CUSTOM_TXT_CDS <Q_REV>
J 0
(5691 -1247);
DISPLAY 1.212766 (5691 -1247);
FORCEPROP 1 LAST CUSTOM_TXT_CDS <CON_PAGE_NUM> OF <CON_TOTAL_PAGES>
J 0
(5429 -1332);
DISPLAY 0.978723 (5429 -1332);
FORCEPROP 1 LAST Q_TITLE DDR5 - CPU0 CHF DIMM2(BLACK)
J 0
(-3491 -1324);
DISPLAY 2.446809 (-3491 -1324);
PAINT GREEN (-3491 -1324);
FORCEPROP 1 LAST Q_DEPT 
J 1
(2112 -1301);
DISPLAY 1.957447 (2112 -1301);
PAINT GREEN (2112 -1301);
FORCEPROP 1 LAST COMMENT_BODY TRUE
J 0
(5887 -1363);
DISPLAY 0.978723 (5887 -1363);
PAINT GREEN (5887 -1363);
DISPLAY INVISIBLE (5887 -1363);
FORCEPROP 2 LAST CDS_XR_PAGE_TITLE CR-93 : @S9S_MB_2U_LIB.S9S_MB_2U(SCH_1):PAGE93
J 0
(-2015 3900);
DISPLAY 0.638298 (-2015 3900);
PAINT PINK (-2015 3900);
DISPLAY INVISIBLE (-2015 3900);
FORCEPROP 2 LAST PAGE_BORDER TRUE
J 0
(-2015 3900);
DISPLAY 0.638298 (-2015 3900);
PAINT PINK (-2015 3900);
DISPLAY INVISIBLE (-2015 3900);
FORCEPROP 1 LAST CDS_LMAN_SYM_OUTLINE -9475,6775,100,-125
J 0
(5875 -1350);
DISPLAY 0.468085 (5875 -1350);
PAINT GREEN (5875 -1350);
DISPLAY INVISIBLE (5875 -1350);
FORCEPROP 2 LAST CDS_LIB pure_quanta
J 0
(5875 -1350);
PAINT MONO (5875 -1350);
DISPLAY INVISIBLE (5875 -1350);
WIRE 17 -1 (-2125 3000)(-2125 3050);
WIRE 17 -1 (-2125 2950)(-2125 3000);
WIRE 17 -1 (-2950 3050)(-2125 3050);
FORCEPROP 2 LAST SIG_NAME M_F_CPU0_SA_CB<7:0>
J 0
(-2860 3060);
DISPLAY 0.680851 (-2860 3060);
PAINT WHITE (-2860 3060);
WIRE 17 -1 (-2125 2900)(-2125 2950);
WIRE 17 -1 (-2125 2850)(-2125 2900);
WIRE 17 -1 (-2125 2800)(-2125 2850);
WIRE 17 -1 (-2125 2750)(-2125 2800);
WIRE 17 -1 (-2125 2550)(-2125 2600);
WIRE 17 -1 (-2125 2500)(-2125 2550);
WIRE 17 -1 (-2950 2600)(-2125 2600);
FORCEPROP 2 LAST SIG_NAME M_F_CPU0_SB_CB<7:0>
J 0
(-2860 2610);
DISPLAY 0.680851 (-2860 2610);
PAINT WHITE (-2860 2610);
WIRE 17 -1 (-2125 4150)(-2125 4200);
WIRE 17 -1 (-2125 4200)(-2125 4250);
WIRE 17 -1 (-2125 4250)(-2125 4300);
WIRE 17 -1 (-2125 4300)(-2125 4350);
WIRE 17 -1 (-2125 4350)(-2125 4400);
WIRE 17 -1 (-2125 4400)(-2125 4450);
WIRE 17 -1 (-2950 4450)(-2125 4450);
FORCEPROP 2 LAST SIG_NAME M_F_CPU0_SA_CA<6:0>
J 0
(-2860 4460);
DISPLAY 0.680851 (-2860 4460);
PAINT WHITE (-2860 4460);
WIRE 17 -1 (-2125 3750)(-2125 3800);
WIRE 17 -1 (-2125 3800)(-2125 3850);
WIRE 17 -1 (-2125 3850)(-2125 3900);
WIRE 17 -1 (-2125 3900)(-2125 3950);
WIRE 17 -1 (-2125 3950)(-2125 4000);
WIRE 17 -1 (-2125 4000)(-2125 4050);
WIRE 17 -1 (-2950 4050)(-2125 4050);
FORCEPROP 2 LAST SIG_NAME M_F_CPU0_SB_CA<6:0>
J 0
(-2860 4060);
DISPLAY 0.680851 (-2860 4060);
PAINT WHITE (-2860 4060);
WIRE 17 -1 (-2125 2700)(-2125 2750);
WIRE 17 -1 (-2125 2450)(-2125 2500);
WIRE 17 -1 (-2125 2400)(-2125 2450);
WIRE 17 -1 (-2125 2350)(-2125 2400);
WIRE 17 -1 (-2125 2300)(-2125 2350);
WIRE 17 -1 (-2125 2250)(-2125 2300);
WIRE 17 -1 (-375 4350)(-375 4400);
WIRE 17 -1 (-375 4300)(-375 4350);
WIRE 17 -1 (-375 4400)(-375 4450);
WIRE 17 -1 (-375 4450)(350 4450);
FORCEPROP 2 LAST SIG_NAME M_F_CPU0_SA_DQ<31:0>
J 0
(-310 4460);
DISPLAY 0.680851 (-310 4460);
PAINT WHITE (-310 4460);
WIRE 17 -1 (-375 4250)(-375 4300);
WIRE 17 -1 (-375 4200)(-375 4250);
WIRE 17 -1 (-375 4150)(-375 4200);
WIRE 17 -1 (-375 4100)(-375 4150);
WIRE 17 -1 (-375 4050)(-375 4100);
WIRE 17 -1 (-375 4000)(-375 4050);
WIRE 17 -1 (-375 3950)(-375 4000);
WIRE 17 -1 (-375 3900)(-375 3950);
WIRE 17 -1 (-375 3850)(-375 3900);
WIRE 17 -1 (-375 3800)(-375 3850);
WIRE 17 -1 (-375 3750)(-375 3800);
WIRE 17 -1 (-375 3700)(-375 3750);
WIRE 17 -1 (-375 3650)(-375 3700);
WIRE 17 -1 (-375 3600)(-375 3650);
WIRE 17 -1 (-375 3550)(-375 3600);
WIRE 17 -1 (-375 3500)(-375 3550);
WIRE 17 -1 (-375 3450)(-375 3500);
WIRE 17 -1 (-375 3400)(-375 3450);
WIRE 17 -1 (-375 3350)(-375 3400);
WIRE 17 -1 (-375 3300)(-375 3350);
WIRE 17 -1 (-375 3250)(-375 3300);
WIRE 17 -1 (-375 3200)(-375 3250);
WIRE 17 -1 (-375 3150)(-375 3200);
WIRE 17 -1 (-375 3100)(-375 3150);
WIRE 17 -1 (-375 3050)(-375 3100);
WIRE 17 -1 (-375 3000)(-375 3050);
WIRE 17 -1 (-375 2950)(-375 3000);
WIRE 17 -1 (-375 2900)(-375 2950);
WIRE 17 -1 (-375 2700)(-375 2750);
WIRE 17 -1 (-375 2650)(-375 2700);
WIRE 17 -1 (-375 2750)(-375 2800);
WIRE 17 -1 (-375 2800)(350 2800);
FORCEPROP 2 LAST SIG_NAME M_F_CPU0_SB_DQ<31:0>
J 0
(-310 2810);
DISPLAY 0.680851 (-310 2810);
PAINT WHITE (-310 2810);
WIRE 17 -1 (-375 2600)(-375 2650);
WIRE 17 -1 (-375 2550)(-375 2600);
WIRE 17 -1 (-375 2500)(-375 2550);
WIRE 17 -1 (-375 2450)(-375 2500);
WIRE 17 -1 (-375 2400)(-375 2450);
WIRE 17 -1 (-375 2350)(-375 2400);
WIRE 17 -1 (-375 2300)(-375 2350);
WIRE 17 -1 (-375 2250)(-375 2300);
WIRE 17 -1 (-375 2200)(-375 2250);
WIRE 17 -1 (-375 2150)(-375 2200);
WIRE 17 -1 (-375 2100)(-375 2150);
WIRE 17 -1 (-375 2050)(-375 2100);
WIRE 17 -1 (-375 2000)(-375 2050);
WIRE 17 -1 (-375 1950)(-375 2000);
WIRE 17 -1 (-375 1900)(-375 1950);
WIRE 17 -1 (-375 1850)(-375 1900);
WIRE 17 -1 (-375 1800)(-375 1850);
WIRE 17 -1 (-375 1750)(-375 1800);
WIRE 17 -1 (-375 1700)(-375 1750);
WIRE 17 -1 (-375 1650)(-375 1700);
WIRE 17 -1 (-375 1600)(-375 1650);
WIRE 17 -1 (-375 1550)(-375 1600);
WIRE 17 -1 (-375 1500)(-375 1550);
WIRE 17 -1 (-375 1450)(-375 1500);
WIRE 17 -1 (-375 1400)(-375 1450);
WIRE 17 -1 (-375 1350)(-375 1400);
WIRE 17 -1 (-375 1300)(-375 1350);
WIRE 17 -1 (-375 1250)(-375 1300);
WIRE 17 -1 (2375 2500)(2375 2600);
WIRE 17 -1 (2375 2600)(2375 2700);
WIRE 17 -1 (2375 2700)(2375 2800);
WIRE 17 -1 (2375 2900)(2375 2800);
WIRE 17 -1 (2375 2900)(2375 3000);
WIRE 17 -1 (2375 3000)(2375 3100);
WIRE 17 -1 (2375 3100)(2375 3200);
WIRE 17 -1 (2375 3200)(2375 3300);
WIRE 17 -1 (2375 3300)(2375 3400);
WIRE 17 -1 (2375 3400)(3400 3400);
FORCEPROP 2 LAST SIG_NAME M_F_CPU0_SB_DQS_DP<9:0>
J 0
(2615 3410);
DISPLAY 0.680851 (2615 3410);
PAINT WHITE (2615 3410);
WIRE 17 -1 (2375 3550)(2375 3650);
WIRE 17 -1 (2375 3650)(2375 3750);
WIRE 17 -1 (2375 3750)(2375 3850);
WIRE 17 -1 (2375 3950)(2375 3850);
WIRE 17 -1 (2375 3950)(2375 4050);
WIRE 17 -1 (2375 4050)(2375 4150);
WIRE 17 -1 (2375 4150)(2375 4250);
WIRE 17 -1 (2375 4250)(2375 4350);
WIRE 17 -1 (2375 4350)(2375 4450);
WIRE 17 -1 (2375 4450)(3400 4450);
FORCEPROP 2 LAST SIG_NAME M_F_CPU0_SA_DQS_DP<9:0>
J 0
(2615 4460);
DISPLAY 0.680851 (2615 4460);
PAINT WHITE (2615 4460);
WIRE 17 -1 (2550 2550)(2550 2650);
WIRE 17 -1 (2550 2450)(2550 2550);
WIRE 17 -1 (2550 2650)(2550 2750);
WIRE 17 -1 (2550 2850)(2550 2750);
WIRE 17 -1 (2550 2850)(2550 2950);
WIRE 17 -1 (2550 2950)(2550 3050);
WIRE 17 -1 (2550 3050)(2550 3150);
WIRE 17 -1 (2550 3150)(2550 3250);
WIRE 17 -1 (2550 3250)(2550 3350);
WIRE 17 -1 (2550 3350)(3400 3350);
FORCEPROP 2 LAST SIG_NAME M_F_CPU0_SB_DQS_DN<9:0>
J 0
(2615 3360);
DISPLAY 0.680851 (2615 3360);
PAINT WHITE (2615 3360);
WIRE 17 -1 (2550 3600)(2550 3700);
WIRE 17 -1 (2550 3500)(2550 3600);
WIRE 17 -1 (2550 3700)(2550 3800);
WIRE 17 -1 (2550 3900)(2550 3800);
WIRE 17 -1 (2550 3900)(2550 4000);
WIRE 17 -1 (2550 4000)(2550 4100);
WIRE 17 -1 (2550 4100)(2550 4200);
WIRE 17 -1 (2550 4200)(2550 4300);
WIRE 17 -1 (2550 4300)(2550 4400);
WIRE 17 -1 (2550 4400)(3400 4400);
FORCEPROP 2 LAST SIG_NAME M_F_CPU0_SA_DQS_DN<9:0>
J 0
(2615 4410);
DISPLAY 0.680851 (2615 4410);
PAINT WHITE (2615 4410);
WIRE 16 -1 (-2900 2250)(-2900 1975);
WIRE 16 -1 (4000 4925)(4000 4425);
WIRE 16 -1 (2300 825)(2300 775);
WIRE 16 -1 (1300 650)(1300 825);
WIRE 16 -1 (5700 1075)(5700 775);
WIRE 16 -1 (5700 1125)(5700 1075);
WIRE 16 -1 (5450 1075)(5700 1075);
WIRE 16 -1 (4000 775)(4000 1175);
WIRE 16 -1 (2925 225)(2925 300);
WIRE 16 -1 (1300 450)(1300 225);
WIRE 16 -1 (-1850 100)(-1850 175);
WIRE 16 3135 (950 1050)(950 -250);
WIRE 16 3135 (3550 1050)(950 1050);
WIRE 16 3135 (950 -250)(3550 -250);
WIRE 16 3135 (3550 -250)(3550 1050);
WIRE 16 -1 (2300 300)(2300 450);
WIRE 16 -1 (2925 300)(2300 300);
WIRE 16 -1 (2925 300)(2925 450);
WIRE 16 -1 (-3350 1725)(-3150 1725);
WIRE 16 -1 (-3350 1825)(-3350 1725);
WIRE 16 -1 (-1850 1825)(-3350 1825);
FORCEPROP 2 LAST SIG_NAME I3C_SPD_DDREFGH_CPU0_LVC1_SCL_R4
J 0
(-2935 1835);
DISPLAY 0.680851 (-2935 1835);
PAINT WHITE (-2935 1835);
WIRE 16 -1 (-1850 1875)(-2875 1875);
FORCEPROP 2 LAST SIG_NAME I3C_SPD_DDREFGH_CPU0_LVC1_SDA
J 0
(-2860 1885);
DISPLAY 0.680851 (-2860 1885);
PAINT WHITE (-2860 1885);
WIRE 16 -1 (-2900 1975)(-1850 1975);
WIRE 16 -1 (-1850 2075)(-2950 2075);
FORCEPROP 2 LAST SIG_NAME M_F_CPU0_ALERT_N
J 0
(-2862 2084);
DISPLAY 0.680851 (-2862 2084);
PAINT WHITE (-2862 2084);
WIRE 16 -1 (-2250 2125)(-1850 2125);
WIRE 16 -1 (-2250 2175)(-2950 2175);
FORCEPROP 2 LAST SIG_NAME RST_M_EF_CPU0_FPGA_N
J 0
(-2862 2184);
DISPLAY 0.680851 (-2862 2184);
PAINT WHITE (-2862 2184);
WIRE 16 -1 (-2250 2175)(-2250 2125);
WIRE 16 -1 (-1850 1925)(-2875 1925);
FORCEPROP 2 LAST SIG_NAME PD_CHF_CPU0_DIMM2_SAA
J 0
(-2860 1935);
DISPLAY 0.680851 (-2860 1935);
PAINT WHITE (-2860 1935);
WIRE 16 -1 (-1750 1725)(-2950 1725);
FORCEPROP 2 LAST SIG_NAME I3C_SPD_DDREFGH_CPU0_LVC1_SCL
J 0
(-2710 1735);
DISPLAY 0.680851 (-2710 1735);
PAINT WHITE (-2710 1735);
WIRE 16 -1 (-1750 1725)(-1750 1675);
WIRE 16 -1 (-1750 1675)(-1775 1675);
WIRE 16 -1 (-1850 1375)(-2950 1375);
FORCEPROP 2 LAST SIG_NAME TP_CHF_CPU0_DIMM2_FRU_4
J 0
(-2862 1384);
DISPLAY 0.680851 (-2862 1384);
PAINT WHITE (-2862 1384);
WIRE 16 -1 (-1850 1425)(-2950 1425);
FORCEPROP 2 LAST SIG_NAME TP_CHF_CPU0_DIMM2_FRU_5
J 0
(-2862 1434);
DISPLAY 0.680851 (-2862 1434);
PAINT WHITE (-2862 1434);
WIRE 16 -1 (-1850 1575)(-2950 1575);
FORCEPROP 2 LAST SIG_NAME PWRGD_CHF_CPU0_DIMM2
J 0
(-2862 1584);
DISPLAY 0.680851 (-2862 1584);
PAINT WHITE (-2862 1584);
WIRE 16 -1 (-650 2525)(-475 2525);
WIRE 16 -1 (2175 4375)(2450 4375);
WIRE 16 -1 (2175 4275)(2450 4275);
WIRE 16 -1 (2175 4175)(2450 4175);
WIRE 16 -1 (2175 4075)(2450 4075);
WIRE 16 -1 (2175 3975)(2450 3975);
WIRE 16 -1 (2175 3875)(2450 3875);
WIRE 16 -1 (2175 3775)(2450 3775);
WIRE 16 -1 (2175 3675)(2450 3675);
WIRE 16 -1 (2175 3475)(2450 3475);
WIRE 16 -1 (2175 3575)(2450 3575);
WIRE 16 -1 (2175 3225)(2450 3225);
WIRE 16 -1 (2175 3325)(2450 3325);
WIRE 16 -1 (2175 3125)(2450 3125);
WIRE 16 -1 (2175 3025)(2450 3025);
WIRE 16 -1 (2175 2925)(2450 2925);
WIRE 16 -1 (2175 2825)(2450 2825);
WIRE 16 -1 (2175 2725)(2450 2725);
WIRE 16 -1 (2175 2625)(2450 2625);
WIRE 16 -1 (2175 2425)(2450 2425);
WIRE 16 -1 (2175 2525)(2450 2525);
WIRE 16 -1 (2175 4125)(2275 4125);
WIRE 16 -1 (2175 4325)(2275 4325);
WIRE 16 -1 (2175 4225)(2275 4225);
WIRE 16 -1 (2175 4425)(2275 4425);
WIRE 16 -1 (2175 3625)(2275 3625);
WIRE 16 -1 (2175 3825)(2275 3825);
WIRE 16 -1 (2175 3725)(2275 3725);
WIRE 16 -1 (2175 3925)(2275 3925);
WIRE 16 -1 (2175 4025)(2275 4025);
WIRE 16 -1 (2175 3075)(2275 3075);
WIRE 16 -1 (2175 3175)(2275 3175);
WIRE 16 -1 (2175 3275)(2275 3275);
WIRE 16 -1 (2175 3525)(2275 3525);
WIRE 16 -1 (2175 3375)(2275 3375);
WIRE 16 -1 (2175 2575)(2275 2575);
WIRE 16 -1 (2175 2775)(2275 2775);
WIRE 16 -1 (2175 2675)(2275 2675);
WIRE 16 -1 (2175 2875)(2275 2875);
WIRE 16 -1 (2175 2975)(2275 2975);
WIRE 16 -1 (2175 2475)(2275 2475);
WIRE 16 -1 (-650 4425)(-475 4425);
WIRE 16 -1 (-650 4375)(-475 4375);
WIRE 16 -1 (-650 2775)(-475 2775);
WIRE 16 -1 (-2025 2725)(-1850 2725);
WIRE 16 -1 (-650 1725)(-475 1725);
WIRE 16 -1 (4250 4325)(4000 4325);
WIRE 16 -1 (4000 4375)(4000 4325);
WIRE 16 -1 (4000 4375)(4250 4375);
WIRE 16 -1 (4000 4425)(4000 4375);
WIRE 16 -1 (4250 4425)(4000 4425);
WIRE 16 -1 (-650 3275)(-475 3275);
WIRE 16 -1 (-650 3225)(-475 3225);
WIRE 16 -1 (-1850 1175)(-2950 1175);
FORCEPROP 2 LAST SIG_NAME TP_CHF_CPU0_DIMM2_FRU_0
J 0
(-2862 1184);
DISPLAY 0.680851 (-2862 1184);
PAINT WHITE (-2862 1184);
WIRE 16 -1 (-1850 1225)(-2950 1225);
FORCEPROP 2 LAST SIG_NAME TP_CHF_CPU0_DIMM2_FRU_1
J 0
(-2862 1234);
DISPLAY 0.680851 (-2862 1234);
PAINT WHITE (-2862 1234);
WIRE 16 -1 (-1850 1275)(-2950 1275);
FORCEPROP 2 LAST SIG_NAME TP_CHF_CPU0_DIMM2_FRU_2
J 0
(-2862 1284);
DISPLAY 0.680851 (-2862 1284);
PAINT WHITE (-2862 1284);
WIRE 16 -1 (-1850 1325)(-2950 1325);
FORCEPROP 2 LAST SIG_NAME TP_CHF_CPU0_DIMM2_FRU_3
J 0
(-2862 1334);
DISPLAY 0.680851 (-2862 1334);
PAINT WHITE (-2862 1334);
WIRE 16 -1 (-1850 1475)(-2950 1475);
FORCEPROP 2 LAST SIG_NAME TP_CHF_CPU0_DIMM2_FRU_6
J 0
(-2862 1484);
DISPLAY 0.680851 (-2862 1484);
PAINT WHITE (-2862 1484);
WIRE 16 -1 (-1850 3575)(-2950 3575);
FORCEPROP 2 LAST SIG_NAME M_F_CPU0_SB_PAR
J 0
(-2862 3584);
DISPLAY 0.680851 (-2862 3584);
PAINT WHITE (-2862 3584);
WIRE 16 -1 (-1850 3625)(-2950 3625);
FORCEPROP 2 LAST SIG_NAME M_F_CPU0_SA_PAR
J 0
(-2862 3634);
DISPLAY 0.680851 (-2862 3634);
PAINT WHITE (-2862 3634);
WIRE 16 -1 (-1850 975)(-2950 975);
FORCEPROP 2 LAST SIG_NAME M_F_CPU0_SB_RSP<1>
J 0
(-2862 984);
DISPLAY 0.680851 (-2862 984);
PAINT WHITE (-2862 984);
WIRE 16 -1 (-1850 1025)(-2950 1025);
FORCEPROP 2 LAST SIG_NAME M_F_CPU0_SA_RSP<1>
J 0
(-2862 1034);
DISPLAY 0.680851 (-2862 1034);
PAINT WHITE (-2862 1034);
WIRE 16 -1 (-650 1225)(-475 1225);
WIRE 16 -1 (-650 1275)(-475 1275);
WIRE 16 -1 (-650 1325)(-475 1325);
WIRE 16 -1 (-650 1375)(-475 1375);
WIRE 16 -1 (-650 1425)(-475 1425);
WIRE 16 -1 (-650 1475)(-475 1475);
WIRE 16 -1 (-650 1525)(-475 1525);
WIRE 16 -1 (-650 1575)(-475 1575);
WIRE 16 -1 (-650 1625)(-475 1625);
WIRE 16 -1 (-650 1675)(-475 1675);
WIRE 16 -1 (-650 1775)(-475 1775);
WIRE 16 -1 (-650 1825)(-475 1825);
WIRE 16 -1 (-650 1875)(-475 1875);
WIRE 16 -1 (-650 1925)(-475 1925);
WIRE 16 -1 (-650 1975)(-475 1975);
WIRE 16 -1 (-650 2025)(-475 2025);
WIRE 16 -1 (-650 2075)(-475 2075);
WIRE 16 -1 (-650 2125)(-475 2125);
WIRE 16 -1 (-650 2175)(-475 2175);
WIRE 16 -1 (-650 2225)(-475 2225);
WIRE 16 -1 (-650 2275)(-475 2275);
WIRE 16 -1 (-650 2325)(-475 2325);
WIRE 16 -1 (-650 2375)(-475 2375);
WIRE 16 -1 (-650 2425)(-475 2425);
WIRE 16 -1 (-650 2475)(-475 2475);
WIRE 16 -1 (-650 2575)(-475 2575);
WIRE 16 -1 (-650 2625)(-475 2625);
WIRE 16 -1 (-650 2675)(-475 2675);
WIRE 16 -1 (-650 2725)(-475 2725);
WIRE 16 -1 (-650 2875)(-475 2875);
WIRE 16 -1 (-650 2925)(-475 2925);
WIRE 16 -1 (-650 2975)(-475 2975);
WIRE 16 -1 (-650 3025)(-475 3025);
WIRE 16 -1 (-650 3075)(-475 3075);
WIRE 16 -1 (-650 3125)(-475 3125);
WIRE 16 -1 (-650 3175)(-475 3175);
WIRE 16 -1 (-650 3325)(-475 3325);
WIRE 16 -1 (-650 3375)(-475 3375);
WIRE 16 -1 (-650 3425)(-475 3425);
WIRE 16 -1 (-650 3475)(-475 3475);
WIRE 16 -1 (-650 3525)(-475 3525);
WIRE 16 -1 (-650 3575)(-475 3575);
WIRE 16 -1 (-650 3625)(-475 3625);
WIRE 16 -1 (-650 3675)(-475 3675);
WIRE 16 -1 (-650 3725)(-475 3725);
WIRE 16 -1 (-650 3775)(-475 3775);
WIRE 16 -1 (-650 3825)(-475 3825);
WIRE 16 -1 (-650 3875)(-475 3875);
WIRE 16 -1 (-650 3925)(-475 3925);
WIRE 16 -1 (-650 3975)(-475 3975);
WIRE 16 -1 (-650 4025)(-475 4025);
WIRE 16 -1 (-650 4075)(-475 4075);
WIRE 16 -1 (-650 4125)(-475 4125);
WIRE 16 -1 (-650 4175)(-475 4175);
WIRE 16 -1 (-650 4225)(-475 4225);
WIRE 16 -1 (-650 4275)(-475 4275);
WIRE 16 -1 (-650 4325)(-475 4325);
WIRE 16 -1 (-1850 3325)(-2950 3325);
FORCEPROP 2 LAST SIG_NAME M_F_CPU0_SB_CS_N<3>
J 0
(-2862 3334);
DISPLAY 0.680851 (-2862 3334);
PAINT WHITE (-2862 3334);
WIRE 16 -1 (-1850 3475)(-2950 3475);
FORCEPROP 2 LAST SIG_NAME M_F_CPU0_SA_CS_N<3>
J 0
(-2862 3484);
DISPLAY 0.680851 (-2862 3484);
PAINT WHITE (-2862 3484);
WIRE 16 -1 (-1850 3275)(-2950 3275);
FORCEPROP 2 LAST SIG_NAME M_F_CPU0_SB_CS_N<2>
J 0
(-2862 3284);
DISPLAY 0.680851 (-2862 3284);
PAINT WHITE (-2862 3284);
WIRE 16 -1 (-1850 3425)(-2950 3425);
FORCEPROP 2 LAST SIG_NAME M_F_CPU0_SA_CS_N<2>
J 0
(-2862 3434);
DISPLAY 0.680851 (-2862 3434);
PAINT WHITE (-2862 3434);
WIRE 16 -1 (-1850 3175)(-2950 3175);
FORCEPROP 2 LAST SIG_NAME M_F_CPU0_CLK_DP<1>
J 0
(-2862 3184);
DISPLAY 0.680851 (-2862 3184);
PAINT WHITE (-2862 3184);
WIRE 16 -1 (-1850 3125)(-2950 3125);
FORCEPROP 2 LAST SIG_NAME M_F_CPU0_CLK_DN<1>
J 0
(-2862 3134);
DISPLAY 0.680851 (-2862 3134);
PAINT WHITE (-2862 3134);
WIRE 16 -1 (-2025 2225)(-1850 2225);
WIRE 16 -1 (-2025 2275)(-1850 2275);
WIRE 16 -1 (-2025 2325)(-1850 2325);
WIRE 16 -1 (-2025 2375)(-1850 2375);
WIRE 16 -1 (-2025 2425)(-1850 2425);
WIRE 16 -1 (-2025 2475)(-1850 2475);
WIRE 16 -1 (-2025 2525)(-1850 2525);
WIRE 16 -1 (-2025 2675)(-1850 2675);
WIRE 16 -1 (-2025 2775)(-1850 2775);
WIRE 16 -1 (-2025 2825)(-1850 2825);
WIRE 16 -1 (-2025 2925)(-1850 2925);
WIRE 16 -1 (-2025 2975)(-1850 2975);
WIRE 16 -1 (-2025 4025)(-1850 4025);
WIRE 16 -1 (-2025 4425)(-1850 4425);
WIRE 16 -1 (-2025 3975)(-1850 3975);
WIRE 16 -1 (-2025 4375)(-1850 4375);
WIRE 16 -1 (-2025 3925)(-1850 3925);
WIRE 16 -1 (-2025 4325)(-1850 4325);
WIRE 16 -1 (-2025 3875)(-1850 3875);
WIRE 16 -1 (-2025 4275)(-1850 4275);
WIRE 16 -1 (-2025 3825)(-1850 3825);
WIRE 16 -1 (-2025 4225)(-1850 4225);
WIRE 16 -1 (-2025 3775)(-1850 3775);
WIRE 16 -1 (-2025 4175)(-1850 4175);
WIRE 16 -1 (-2025 3725)(-1850 3725);
WIRE 16 -1 (-2025 4125)(-1850 4125);
WIRE 16 -1 (-2025 2575)(-1850 2575);
WIRE 16 -1 (-2025 2875)(-1850 2875);
WIRE 16 -1 (-2025 3025)(-1850 3025);
WIRE 16 -1 (4000 1175)(4250 1175);
WIRE 16 -1 (4000 1175)(4000 1225);
WIRE 16 -1 (4000 1225)(4250 1225);
WIRE 16 -1 (4000 1225)(4000 1275);
WIRE 16 -1 (4000 1275)(4250 1275);
WIRE 16 -1 (4000 1275)(4000 1325);
WIRE 16 -1 (4000 1325)(4250 1325);
WIRE 16 -1 (4000 1325)(4000 1375);
WIRE 16 -1 (4000 1375)(4250 1375);
WIRE 16 -1 (4000 1375)(4000 1425);
WIRE 16 -1 (4000 1425)(4250 1425);
WIRE 16 -1 (4000 1425)(4000 1475);
WIRE 16 -1 (4000 1475)(4250 1475);
WIRE 16 -1 (4000 1475)(4000 1525);
WIRE 16 -1 (4000 1525)(4250 1525);
WIRE 16 -1 (4000 1525)(4000 1575);
WIRE 16 -1 (4000 1575)(4250 1575);
WIRE 16 -1 (4000 1575)(4000 1625);
WIRE 16 -1 (4000 1625)(4250 1625);
WIRE 16 -1 (4000 1625)(4000 1675);
WIRE 16 -1 (4250 1675)(4000 1675);
WIRE 16 -1 (4000 1675)(4000 1725);
WIRE 16 -1 (4000 1725)(4250 1725);
WIRE 16 -1 (4000 1725)(4000 1775);
WIRE 16 -1 (4000 1775)(4250 1775);
WIRE 16 -1 (4000 1775)(4000 1825);
WIRE 16 -1 (4000 1825)(4250 1825);
WIRE 16 -1 (4000 1825)(4000 1875);
WIRE 16 -1 (4000 1875)(4250 1875);
WIRE 16 -1 (4000 1875)(4000 1925);
WIRE 16 -1 (4000 1925)(4250 1925);
WIRE 16 -1 (4000 1925)(4000 1975);
WIRE 16 -1 (4000 1975)(4250 1975);
WIRE 16 -1 (4000 1975)(4000 2025);
WIRE 16 -1 (4000 2025)(4250 2025);
WIRE 16 -1 (4000 2025)(4000 2075);
WIRE 16 -1 (4000 2075)(4250 2075);
WIRE 16 -1 (4000 2075)(4000 2125);
WIRE 16 -1 (4000 2125)(4250 2125);
WIRE 16 -1 (4000 2125)(4000 2175);
WIRE 16 -1 (4250 2175)(4000 2175);
WIRE 16 -1 (4000 2175)(4000 2225);
WIRE 16 -1 (4000 2225)(4250 2225);
WIRE 16 -1 (4000 2225)(4000 2275);
WIRE 16 -1 (4000 2275)(4250 2275);
WIRE 16 -1 (4000 2275)(4000 2325);
WIRE 16 -1 (4000 2325)(4250 2325);
WIRE 16 -1 (4000 2325)(4000 2375);
WIRE 16 -1 (4000 2375)(4250 2375);
WIRE 16 -1 (4000 2375)(4000 2425);
WIRE 16 -1 (4000 2425)(4250 2425);
WIRE 16 -1 (4000 2425)(4000 2475);
WIRE 16 -1 (4000 2475)(4250 2475);
WIRE 16 -1 (4000 2475)(4000 2525);
WIRE 16 -1 (4000 2525)(4250 2525);
WIRE 16 -1 (4000 2525)(4000 2575);
WIRE 16 -1 (4000 2575)(4250 2575);
WIRE 16 -1 (4000 2575)(4000 2625);
WIRE 16 -1 (4000 2625)(4250 2625);
WIRE 16 -1 (4000 2625)(4000 2675);
WIRE 16 -1 (4250 2675)(4000 2675);
WIRE 16 -1 (4000 2675)(4000 2725);
WIRE 16 -1 (4000 2725)(4250 2725);
WIRE 16 -1 (4000 2725)(4000 2775);
WIRE 16 -1 (4000 2775)(4250 2775);
WIRE 16 -1 (4000 2775)(4000 2825);
WIRE 16 -1 (4000 2825)(4250 2825);
WIRE 16 -1 (4000 2825)(4000 2875);
WIRE 16 -1 (4000 2875)(4250 2875);
WIRE 16 -1 (4000 2875)(4000 2925);
WIRE 16 -1 (4000 2925)(4250 2925);
WIRE 16 -1 (4000 2925)(4000 2975);
WIRE 16 -1 (4000 2975)(4250 2975);
WIRE 16 -1 (4000 2975)(4000 3025);
WIRE 16 -1 (4000 3025)(4250 3025);
WIRE 16 -1 (4000 3025)(4000 3075);
WIRE 16 -1 (4000 3075)(4250 3075);
WIRE 16 -1 (4000 3075)(4000 3125);
WIRE 16 -1 (4000 3125)(4250 3125);
WIRE 16 -1 (4000 3125)(4000 3175);
WIRE 16 -1 (4250 3175)(4000 3175);
WIRE 16 -1 (4000 3175)(4000 3225);
WIRE 16 -1 (4000 3225)(4250 3225);
WIRE 16 -1 (4000 3225)(4000 3275);
WIRE 16 -1 (4000 3275)(4250 3275);
WIRE 16 -1 (4000 3275)(4000 3325);
WIRE 16 -1 (4000 3325)(4250 3325);
WIRE 16 -1 (4000 3325)(4000 3375);
WIRE 16 -1 (4000 3375)(4250 3375);
WIRE 16 -1 (4000 3375)(4000 3425);
WIRE 16 -1 (4000 3425)(4250 3425);
WIRE 16 -1 (4000 3425)(4000 3475);
WIRE 16 -1 (4000 3475)(4250 3475);
WIRE 16 -1 (4000 3475)(4000 3525);
WIRE 16 -1 (4000 3525)(4250 3525);
WIRE 16 -1 (4000 3525)(4000 3575);
WIRE 16 -1 (4000 3575)(4250 3575);
WIRE 16 -1 (4000 3575)(4000 3625);
WIRE 16 -1 (4000 3625)(4250 3625);
WIRE 16 -1 (4000 3625)(4000 3675);
WIRE 16 -1 (4250 3675)(4000 3675);
WIRE 16 -1 (4000 3675)(4000 3725);
WIRE 16 -1 (4000 3725)(4250 3725);
WIRE 16 -1 (4000 3725)(4000 3775);
WIRE 16 -1 (4000 3775)(4250 3775);
WIRE 16 -1 (4000 3775)(4000 3825);
WIRE 16 -1 (4000 3825)(4250 3825);
WIRE 16 -1 (4000 3825)(4000 3875);
WIRE 16 -1 (4000 3875)(4250 3875);
WIRE 16 -1 (4000 3875)(4000 3925);
WIRE 16 -1 (4000 3925)(4250 3925);
WIRE 16 -1 (4000 3925)(4000 3975);
WIRE 16 -1 (4000 3975)(4250 3975);
WIRE 16 -1 (4000 3975)(4000 4025);
WIRE 16 -1 (4000 4025)(4250 4025);
WIRE 16 -1 (4000 4025)(4000 4075);
WIRE 16 -1 (4000 4075)(4250 4075);
WIRE 16 -1 (4000 4075)(4000 4125);
WIRE 16 -1 (4000 4125)(4250 4125);
WIRE 16 -1 (4000 4125)(4000 4175);
WIRE 16 -1 (4250 4175)(4000 4175);
WIRE 16 -1 (4000 4175)(4000 4225);
WIRE 16 -1 (4000 4225)(4250 4225);
WIRE 16 -1 (4000 4225)(4000 4275);
WIRE 16 -1 (4250 4275)(4000 4275);
WIRE 16 -1 (5450 1125)(5700 1125);
WIRE 16 -1 (5450 1175)(5700 1175);
WIRE 16 -1 (5700 1175)(5700 1125);
WIRE 16 -1 (5450 1275)(5700 1275);
WIRE 16 -1 (5700 1275)(5700 1175);
WIRE 16 -1 (5450 1325)(5700 1325);
WIRE 16 -1 (5700 1325)(5700 1275);
WIRE 16 -1 (5450 1375)(5700 1375);
WIRE 16 -1 (5700 1325)(5700 1375);
WIRE 16 -1 (5450 1425)(5700 1425);
WIRE 16 -1 (5700 1425)(5700 1375);
WIRE 16 -1 (5450 1475)(5700 1475);
WIRE 16 -1 (5700 1475)(5700 1425);
WIRE 16 -1 (5450 1525)(5700 1525);
WIRE 16 -1 (5700 1525)(5700 1475);
WIRE 16 -1 (5450 1575)(5700 1575);
WIRE 16 -1 (5700 1575)(5700 1525);
WIRE 16 -1 (5450 1625)(5700 1625);
WIRE 16 -1 (5700 1625)(5700 1575);
WIRE 16 -1 (5450 1675)(5700 1675);
WIRE 16 -1 (5700 1675)(5700 1625);
WIRE 16 -1 (5700 1725)(5450 1725);
WIRE 16 -1 (5700 1725)(5700 1675);
WIRE 16 -1 (5700 1775)(5450 1775);
WIRE 16 -1 (5700 1775)(5700 1725);
WIRE 16 -1 (5700 1825)(5450 1825);
WIRE 16 -1 (5700 1825)(5700 1775);
WIRE 16 -1 (5450 1875)(5700 1875);
WIRE 16 -1 (5700 1825)(5700 1875);
WIRE 16 -1 (5700 1925)(5450 1925);
WIRE 16 -1 (5700 1875)(5700 1925);
WIRE 16 -1 (5700 1975)(5450 1975);
WIRE 16 -1 (5700 1975)(5700 1925);
WIRE 16 -1 (5700 2025)(5450 2025);
WIRE 16 -1 (5700 2025)(5700 1975);
WIRE 16 -1 (5700 2075)(5700 2025);
WIRE 16 -1 (5700 2075)(5450 2075);
WIRE 16 -1 (5450 2125)(5700 2125);
WIRE 16 -1 (5700 2125)(5700 2075);
WIRE 16 -1 (5450 2175)(5700 2175);
WIRE 16 -1 (5700 2175)(5700 2125);
WIRE 16 -1 (5450 2225)(5700 2225);
WIRE 16 -1 (5700 2175)(5700 2225);
WIRE 16 -1 (5450 2275)(5700 2275);
WIRE 16 -1 (5700 2275)(5700 2225);
WIRE 16 -1 (5450 2325)(5700 2325);
WIRE 16 -1 (5700 2325)(5700 2275);
WIRE 16 -1 (5450 2375)(5700 2375);
WIRE 16 -1 (5700 2375)(5700 2325);
WIRE 16 -1 (5450 2425)(5700 2425);
WIRE 16 -1 (5700 2425)(5700 2375);
WIRE 16 -1 (5450 2475)(5700 2475);
WIRE 16 -1 (5700 2475)(5700 2425);
WIRE 16 -1 (5700 2525)(5450 2525);
WIRE 16 -1 (5700 2525)(5700 2475);
WIRE 16 -1 (5700 2575)(5450 2575);
WIRE 16 -1 (5700 2575)(5700 2525);
WIRE 16 -1 (5450 2625)(5700 2625);
WIRE 16 -1 (5700 2625)(5700 2575);
WIRE 16 -1 (5450 2675)(5700 2675);
WIRE 16 -1 (5700 2675)(5700 2625);
WIRE 16 -1 (5450 2725)(5700 2725);
WIRE 16 -1 (5700 2675)(5700 2725);
WIRE 16 -1 (5450 2775)(5700 2775);
WIRE 16 -1 (5700 2775)(5700 2725);
WIRE 16 -1 (5450 2825)(5700 2825);
WIRE 16 -1 (5700 2825)(5700 2775);
WIRE 16 -1 (5450 2875)(5700 2875);
WIRE 16 -1 (5700 2875)(5700 2825);
WIRE 16 -1 (5450 2925)(5700 2925);
WIRE 16 -1 (5700 2925)(5700 2875);
WIRE 16 -1 (5450 2975)(5700 2975);
WIRE 16 -1 (5700 2975)(5700 2925);
WIRE 16 -1 (5700 3025)(5450 3025);
WIRE 16 -1 (5700 3025)(5700 2975);
WIRE 16 -1 (5700 3075)(5700 3025);
WIRE 16 -1 (5700 3075)(5450 3075);
WIRE 16 -1 (5450 3125)(5700 3125);
WIRE 16 -1 (5700 3125)(5700 3075);
WIRE 16 -1 (5450 3175)(5700 3175);
WIRE 16 -1 (5700 3175)(5700 3125);
WIRE 16 -1 (5450 3225)(5700 3225);
WIRE 16 -1 (5700 3175)(5700 3225);
WIRE 16 -1 (5450 3275)(5700 3275);
WIRE 16 -1 (5700 3275)(5700 3225);
WIRE 16 -1 (5450 3325)(5700 3325);
WIRE 16 -1 (5700 3325)(5700 3275);
WIRE 16 -1 (5450 3375)(5700 3375);
WIRE 16 -1 (5700 3375)(5700 3325);
WIRE 16 -1 (5450 3425)(5700 3425);
WIRE 16 -1 (5700 3425)(5700 3375);
WIRE 16 -1 (5450 3475)(5700 3475);
WIRE 16 -1 (5700 3475)(5700 3425);
WIRE 16 -1 (5700 3525)(5450 3525);
WIRE 16 -1 (5700 3525)(5700 3475);
WIRE 16 -1 (5700 3575)(5450 3575);
WIRE 16 -1 (5700 3575)(5700 3525);
WIRE 16 -1 (5450 3625)(5700 3625);
WIRE 16 -1 (5700 3625)(5700 3575);
WIRE 16 -1 (5450 3675)(5700 3675);
WIRE 16 -1 (5700 3675)(5700 3625);
WIRE 16 -1 (5450 3725)(5700 3725);
WIRE 16 -1 (5700 3675)(5700 3725);
WIRE 16 -1 (5450 3775)(5700 3775);
WIRE 16 -1 (5700 3775)(5700 3725);
WIRE 16 -1 (5450 3825)(5700 3825);
WIRE 16 -1 (5700 3825)(5700 3775);
WIRE 16 -1 (5450 3875)(5700 3875);
WIRE 16 -1 (5700 3875)(5700 3825);
WIRE 16 -1 (5450 3925)(5700 3925);
WIRE 16 -1 (5700 3925)(5700 3875);
WIRE 16 -1 (5450 3975)(5700 3975);
WIRE 16 -1 (5700 3975)(5700 3925);
WIRE 16 -1 (5450 4025)(5700 4025);
WIRE 16 -1 (5700 4025)(5700 3975);
WIRE 16 -1 (5450 4075)(5700 4075);
WIRE 16 -1 (5700 4075)(5700 4025);
WIRE 16 -1 (5700 4125)(5700 4075);
WIRE 16 -1 (5450 4125)(5700 4125);
WIRE 16 -1 (5450 4175)(5700 4175);
WIRE 16 -1 (5700 4175)(5700 4125);
WIRE 16 -1 (5450 4225)(5700 4225);
WIRE 16 -1 (5700 4225)(5700 4175);
WIRE 16 -1 (5450 4275)(5700 4275);
WIRE 16 -1 (5700 4275)(5700 4225);
WIRE 16 -1 (5450 4325)(5700 4325);
WIRE 16 -1 (5700 4325)(5700 4275);
WIRE 16 -1 (5450 4375)(5700 4375);
WIRE 16 -1 (5700 4375)(5700 4325);
WIRE 16 -1 (5700 4425)(5700 4375);
WIRE 16 -1 (5450 4425)(5700 4425);
WIRE 16 -1 (-1850 475)(-2950 475);
FORCEPROP 2 LAST SIG_NAME PD_CHF_CPU0_DIMM2_SAA
J 0
(-2862 484);
DISPLAY 0.680851 (-2862 484);
PAINT WHITE (-2862 484);
WIRE 16 -1 (-1850 375)(-1850 475);
WIRE 16 -1 (2300 775)(2300 650);
WIRE 16 -1 (2925 775)(2300 775);
WIRE 16 -1 (2925 650)(2925 775);
DOT 1 (4000 2075);
DOT 1 (4000 2125);
DOT 1 (5700 1075);
DOT 1 (5700 1125);
DOT 1 (5700 1175);
DOT 1 (5700 1325);
DOT 1 (5700 4375);
DOT 1 (5700 4275);
DOT 1 (5700 4325);
DOT 1 (5700 4225);
DOT 1 (5700 4125);
DOT 1 (5700 4175);
DOT 1 (5700 4025);
DOT 1 (5700 4075);
DOT 1 (5700 3975);
DOT 1 (5700 3925);
DOT 1 (5700 3875);
DOT 1 (5700 3775);
DOT 1 (5700 3825);
DOT 1 (5700 3725);
DOT 1 (5700 3625);
DOT 1 (5700 3675);
DOT 1 (5700 3525);
DOT 1 (5700 3475);
DOT 1 (5700 3575);
DOT 1 (5700 3425);
DOT 1 (5700 3375);
DOT 1 (5700 3225);
DOT 1 (5700 3275);
DOT 1 (5700 3325);
DOT 1 (5700 3125);
DOT 1 (5700 3175);
DOT 1 (5700 3075);
DOT 1 (5700 3025);
DOT 1 (5700 2975);
DOT 1 (5700 2875);
DOT 1 (5700 2925);
DOT 1 (5700 2825);
DOT 1 (5700 2775);
DOT 1 (5700 2725);
DOT 1 (5700 2625);
DOT 1 (5700 2575);
DOT 1 (5700 2675);
DOT 1 (5700 2525);
DOT 1 (5700 2475);
DOT 1 (5700 2325);
DOT 1 (5700 2375);
DOT 1 (5700 2425);
DOT 1 (5700 2275);
DOT 1 (5700 2225);
DOT 1 (5700 2075);
DOT 1 (5700 2125);
DOT 1 (5700 2175);
DOT 1 (5700 1975);
DOT 1 (5700 2025);
DOT 1 (5700 1925);
DOT 1 (5700 1875);
DOT 1 (5700 1825);
DOT 1 (5700 1725);
DOT 1 (5700 1775);
DOT 1 (5700 1675);
DOT 1 (5700 1575);
DOT 1 (5700 1625);
DOT 1 (5700 1425);
DOT 1 (5700 1525);
DOT 1 (5700 1375);
DOT 1 (5700 1275);
DOT 1 (4000 4225);
DOT 1 (4000 4175);
DOT 1 (4000 4125);
DOT 1 (4000 4075);
DOT 1 (4000 4025);
DOT 1 (4000 3975);
DOT 1 (4000 3925);
DOT 1 (4000 3875);
DOT 1 (4000 3825);
DOT 1 (4000 3775);
DOT 1 (4000 3725);
DOT 1 (4000 3675);
DOT 1 (4000 3575);
DOT 1 (4000 3525);
DOT 1 (4000 3475);
DOT 1 (4000 3425);
DOT 1 (4000 3375);
DOT 1 (4000 3325);
DOT 1 (4000 3275);
DOT 1 (4000 3225);
DOT 1 (4000 3175);
DOT 1 (4000 3125);
DOT 1 (4000 3075);
DOT 1 (4000 3025);
DOT 1 (4000 2975);
DOT 1 (4000 2925);
DOT 1 (4000 2875);
DOT 1 (4000 2825);
DOT 1 (4000 2775);
DOT 1 (4000 2725);
DOT 1 (4000 2675);
DOT 1 (4000 2625);
DOT 1 (4000 2575);
DOT 1 (4000 2525);
DOT 1 (4000 2475);
DOT 1 (4000 2425);
DOT 1 (4000 2375);
DOT 1 (4000 2325);
DOT 1 (4000 2275);
DOT 1 (4000 2225);
DOT 1 (4000 2175);
DOT 1 (4000 2025);
DOT 1 (4000 1975);
DOT 1 (4000 1925);
DOT 1 (4000 1875);
DOT 1 (4000 1825);
DOT 1 (4000 1775);
DOT 1 (4000 1725);
DOT 1 (4000 1675);
DOT 1 (4000 1575);
DOT 1 (4000 1525);
DOT 1 (4000 1475);
DOT 1 (4000 1425);
DOT 1 (4000 1375);
DOT 1 (4000 1325);
DOT 1 (4000 1275);
DOT 1 (4000 1225);
DOT 1 (4000 1175);
DOT 1 (2925 300);
DOT 1 (2300 775);
DOT 1 (5700 1475);
DOT 1 (4000 3625);
DOT 1 (4000 1625);
DOT 1 (4000 4375);
DOT 1 (4000 4425);
FORCENOTE
20210728 MODIFY FOR GT
(-3350 5125) 0;
DISPLAY LEFT (-3350 5125);
DISPLAY 2.510638 (-3350 5125);
PAINT PINK (-3350 5125);
QUIT
